G04 ================== begin FILE IDENTIFICATION RECORD ==================*
G04 Layout Name:  D:/<user>/Wistron_project/16317-1/gbr/16317-1.brd*
G04 Film Name:    DP_REF_L1*
G04 File Format:  Gerber RS274X*
G04 File Origin:  Cadence Allegro 16.5-S056*
G04 Origin Date:  Fri Jun 09 15:53:51 2017*
G04 *
G04 Layer:  BOARD GEOMETRY/DP_REF_L1_TBL*
G04 Layer:  BOARD GEOMETRY/DP_REF_L1_TOP*
G04 Layer:  BOARD GEOMETRY/PANEL_OUTLINE*
G04 *
G04 Offset:    (0.00 0.00)*
G04 Mirror:    No*
G04 Mode:      Positive*
G04 Rotation:  0*
G04 FullContactRelief:  No*
G04 UndefLineWidth:     6.00*
G04 ================== end FILE IDENTIFICATION RECORD ====================*
%FSLAX35Y35*MOIN*%
%IR0*IPPOS*OFA0.00000B0.00000*MIA0B0*SFA1.00000B1.00000*%
%ADD10C,.02*%
%ADD11C,.005*%
%ADD12C,.006*%
G75*
%LPD*%
G75*
G54D10*
G01X1985143Y1416035D02*
X2720143D01*
G01X1985143Y1381385D02*
X2720143D01*
G01X1985143Y1485335D02*
Y1381385D01*
G01Y1485335D02*
X2720143D01*
G01X1985143Y1450685D02*
X2720143D01*
G01X2160143Y1485335D02*
Y1381385D01*
G01X2405143Y1485335D02*
Y1381385D01*
G01X2510143Y1485335D02*
Y1381385D01*
G01X2720143Y1485335D02*
Y1381385D01*
G54D11*
G01X131193Y58444D02*
X134357D01*
G01X130731Y59594D02*
X134357D01*
G01X130731D02*
X134357D01*
G01X131193Y58444D02*
X134357D01*
G01X124463Y74394D02*
X127488D01*
G01X124463Y73244D02*
X127488D01*
G01X124463D02*
X127488D01*
G01X124463Y74394D02*
X127488D01*
G01X124880Y58244D02*
X124463D01*
G01X124880Y59394D02*
X124463D01*
G01X124880D02*
X124463D01*
G01X124880Y58244D02*
X124463D01*
G01X131193Y511200D02*
X134357D01*
G01X130731Y512350D02*
X134357D01*
G01X130731D02*
X134357D01*
G01X131193Y511200D02*
X134357D01*
G01X124463Y527150D02*
X127488D01*
G01X124463Y526000D02*
X127488D01*
G01X124463D02*
X127488D01*
G01X124463Y527150D02*
X127488D01*
G01X124880Y511000D02*
X124463D01*
G01X124880Y512150D02*
X124463D01*
G01X124880D02*
X124463D01*
G01X124880Y511000D02*
X124463D01*
G01X131193Y963956D02*
X134357D01*
G01X130731Y965106D02*
X134357D01*
G01X130731D02*
X134357D01*
G01X131193Y963956D02*
X134357D01*
G01X124463Y979906D02*
X127488D01*
G01X124463Y978756D02*
X127488D01*
G01X124463D02*
X127488D01*
G01X124463Y979906D02*
X127488D01*
G01X124880Y963756D02*
X124463D01*
G01X124880Y964906D02*
X124463D01*
G01X124880D02*
X124463D01*
G01X124880Y963756D02*
X124463D01*
G01X255405Y58444D02*
X258569D01*
G01X254943Y59594D02*
X258569D01*
G01X254943D02*
X258569D01*
G01X255405Y58444D02*
X258569D01*
G01X248675Y74394D02*
X251700D01*
G01X248675Y73244D02*
X251700D01*
G01X248675D02*
X251700D01*
G01X248675Y74394D02*
X251700D01*
G01X249092Y58244D02*
X248675D01*
G01X249092Y59394D02*
X248675D01*
G01X249092D02*
X248675D01*
G01X249092Y58244D02*
X248675D01*
G01X255405Y511200D02*
X258569D01*
G01X254943Y512350D02*
X258569D01*
G01X254943D02*
X258569D01*
G01X255405Y511200D02*
X258569D01*
G01X248550Y527150D02*
X251700D01*
G01X248675Y526000D02*
X251700D01*
G01X248675D02*
X251700D01*
G01X248550Y527150D02*
X251700D01*
G01X249092Y511000D02*
X248675D01*
G01X249092Y512150D02*
X248675D01*
G01X249092D02*
X248675D01*
G01X249092Y511000D02*
X248675D01*
G01X255405Y963956D02*
X258569D01*
G01X254943Y965106D02*
X258569D01*
G01X254943D02*
X258569D01*
G01X255405Y963956D02*
X258569D01*
G01X248675Y979906D02*
X251700D01*
G01X248756Y978756D02*
X251700D01*
G01X248756D02*
X251700D01*
G01X248675Y979906D02*
X251700D01*
G01X249092Y963756D02*
X248675D01*
G01X249092Y964906D02*
X248675D01*
G01X249092D02*
X248675D01*
G01X249092Y963756D02*
X248675D01*
G01X379618Y58444D02*
X382782D01*
G01X379156Y59594D02*
X382782D01*
G01X379156D02*
X382782D01*
G01X379618Y58444D02*
X382782D01*
G01X372888Y74394D02*
X375913D01*
G01X372888Y73244D02*
X375913D01*
G01X372888D02*
X375913D01*
G01X372888Y74394D02*
X375913D01*
G01X373305Y58244D02*
X372888D01*
G01X373305Y59394D02*
X372888D01*
G01X373305D02*
X372888D01*
G01X373305Y58244D02*
X372888D01*
G01X379618Y511200D02*
X382782D01*
G01X379156Y512350D02*
X382782D01*
G01X379156D02*
X382782D01*
G01X379618Y511200D02*
X382782D01*
G01X372888Y527150D02*
X375913D01*
G01X372888Y526000D02*
X375913D01*
G01X372888D02*
X375913D01*
G01X372888Y527150D02*
X375913D01*
G01X373305Y511000D02*
X372888D01*
G01X373305Y512150D02*
X372888D01*
G01X373305D02*
X372888D01*
G01X373305Y511000D02*
X372888D01*
G01X379618Y963956D02*
X382782D01*
G01X379156Y965106D02*
X382782D01*
G01X379156D02*
X382782D01*
G01X379618Y963956D02*
X382782D01*
G01X372888Y979906D02*
X375913D01*
G01X372888Y978756D02*
X375913D01*
G01X372888D02*
X375913D01*
G01X372888Y979906D02*
X375913D01*
G01X373305Y963756D02*
X372888D01*
G01X373305Y964906D02*
X372888D01*
G01X373305D02*
X372888D01*
G01X373305Y963756D02*
X372888D01*
G01X503830Y58444D02*
X506994D01*
G01X503368Y59594D02*
X506994D01*
G01X503368D02*
X506994D01*
G01X503830Y58444D02*
X506994D01*
G01X497100Y74394D02*
X500125D01*
G01X497100Y73244D02*
X500125D01*
G01X497100D02*
X500125D01*
G01X497100Y74394D02*
X500125D01*
G01X497517Y58244D02*
X497100D01*
G01X497517Y59394D02*
X497100D01*
G01X497517D02*
X497100D01*
G01X497517Y58244D02*
X497100D01*
G01X503830Y511200D02*
X506994D01*
G01X503368Y512350D02*
X506994D01*
G01X503368D02*
X506994D01*
G01X503830Y511200D02*
X506994D01*
G01X497100Y527150D02*
X500125D01*
G01X497100Y526000D02*
X500125D01*
G01X497100D02*
X500125D01*
G01X497100Y527150D02*
X500125D01*
G01X497517Y511000D02*
X497100D01*
G01X497517Y512150D02*
X497100D01*
G01X497517D02*
X497100D01*
G01X497517Y511000D02*
X497100D01*
G01X503830Y963956D02*
X506994D01*
G01X503368Y965106D02*
X506994D01*
G01X503368D02*
X506994D01*
G01X503830Y963956D02*
X506994D01*
G01X497100Y979906D02*
X500125D01*
G01X497100Y978756D02*
X500125D01*
G01X497100D02*
X500125D01*
G01X497100Y979906D02*
X500125D01*
G01X497517Y963756D02*
X497100D01*
G01X497517Y964906D02*
X497100D01*
G01X497517D02*
X497100D01*
G01X497517Y963756D02*
X497100D01*
G01X628043Y58444D02*
X631207D01*
G01X627581Y59594D02*
X631207D01*
G01X627581D02*
X631207D01*
G01X628043Y58444D02*
X631207D01*
G01X621313Y74394D02*
X624338D01*
G01X621313Y73244D02*
X624338D01*
G01X621313D02*
X624338D01*
G01X621313Y74394D02*
X624338D01*
G01X621730Y58244D02*
X621313D01*
G01X621730Y59394D02*
X621313D01*
G01X621730D02*
X621313D01*
G01X621730Y58244D02*
X621313D01*
G01X628043Y511200D02*
X631207D01*
G01X627581Y512350D02*
X631207D01*
G01X627581D02*
X631207D01*
G01X628043Y511200D02*
X631207D01*
G01X621250Y527150D02*
X624338D01*
G01X621313Y526000D02*
X624338D01*
G01X621313D02*
X624338D01*
G01X621250Y527150D02*
X624338D01*
G01X621730Y511000D02*
X621313D01*
G01X621730Y512150D02*
X621313D01*
G01X621730D02*
X621313D01*
G01X621730Y511000D02*
X621313D01*
G01X628043Y963956D02*
X631207D01*
G01X627581Y965106D02*
X631207D01*
G01X627581D02*
X631207D01*
G01X628043Y963956D02*
X631207D01*
G01X621313Y979906D02*
X624338D01*
G01X621313Y978756D02*
X624338D01*
G01X621313D02*
X624338D01*
G01X621313Y979906D02*
X624338D01*
G01X621730Y963756D02*
X621313D01*
G01X621730Y964906D02*
X621313D01*
G01X621730D02*
X621313D01*
G01X621730Y963756D02*
X621313D01*
G01X752256Y58444D02*
X755420D01*
G01X751794Y59594D02*
X755420D01*
G01X751794D02*
X755420D01*
G01X752256Y58444D02*
X755420D01*
G01X745406Y74394D02*
X748551D01*
G01X745526Y73244D02*
X748551D01*
G01X745526D02*
X748551D01*
G01X745406Y74394D02*
X748551D01*
G01X745943Y58244D02*
X745526D01*
G01X745943Y59394D02*
X745526D01*
G01X745943D02*
X745526D01*
G01X745943Y58244D02*
X745526D01*
G01X752256Y511200D02*
X755420D01*
G01X751794Y512350D02*
X755420D01*
G01X751794D02*
X755420D01*
G01X752256Y511200D02*
X755420D01*
G01X745526Y527150D02*
X748551D01*
G01X745526Y526000D02*
X748551D01*
G01X745526D02*
X748551D01*
G01X745526Y527150D02*
X748551D01*
G01X745943Y511000D02*
X745526D01*
G01X745943Y512150D02*
X745526D01*
G01X745943D02*
X745526D01*
G01X745943Y511000D02*
X745526D01*
G01X752256Y963956D02*
X755420D01*
G01X751794Y965106D02*
X755420D01*
G01X751794D02*
X755420D01*
G01X752256Y963956D02*
X755420D01*
G01X745394Y979906D02*
X748551D01*
G01X745526Y978756D02*
X748551D01*
G01X745526D02*
X748551D01*
G01X745394Y979906D02*
X748551D01*
G01X745943Y963756D02*
X745526D01*
G01X745943Y964906D02*
X745526D01*
G01X745943D02*
X745526D01*
G01X745943Y963756D02*
X745526D01*
G01X1259575Y57225D02*
Y54325D01*
G01X1258425Y57702D02*
Y54325D01*
G01X1260494Y58144D02*
X1259575Y57225D01*
G01X1260017Y59294D02*
X1258425Y57702D01*
G01X1263449Y58144D02*
X1260494D01*
G01X1263249Y59294D02*
X1260017D01*
G01X1258425Y57702D02*
Y54325D01*
G01X1259575Y57225D02*
Y54325D01*
G01X1260017Y59294D02*
X1258425Y57702D01*
G01X1260494Y58144D02*
X1259575Y57225D01*
G01X1263249Y59294D02*
X1260017D01*
G01X1263449Y58144D02*
X1260494D01*
G01X1272325Y72602D02*
Y69325D01*
G01X1273475Y72125D02*
Y69325D01*
G01X1273977Y74254D02*
X1272325Y72602D01*
G01X1274454Y73104D02*
X1273475Y72125D01*
G01X1282484Y74254D02*
X1273977D01*
G01X1282764Y73104D02*
X1274454D01*
G01X1273475Y72125D02*
Y69325D01*
G01X1272325Y72602D02*
Y69325D01*
G01X1274454Y73104D02*
X1273475Y72125D01*
G01X1273977Y74254D02*
X1272325Y72602D01*
G01X1282764Y73104D02*
X1274454D01*
G01X1282484Y74254D02*
X1273977D01*
G01X1269318Y58244D02*
X1282624D01*
G01X1269350Y59394D02*
X1282624D01*
G01X1269350D02*
X1282624D01*
G01X1269318Y58244D02*
X1282624D01*
G01X1259575Y509981D02*
Y507025D01*
G01X1258425Y510458D02*
Y507025D01*
G01X1260459Y510865D02*
X1259575Y509981D01*
G01X1259982Y512015D02*
X1258425Y510458D01*
G01X1263484Y510865D02*
X1260459D01*
G01X1263214Y512015D02*
X1259982D01*
G01X1258425Y510458D02*
Y507025D01*
G01X1259575Y509981D02*
Y507025D01*
G01X1259982Y512015D02*
X1258425Y510458D01*
G01X1260459Y510865D02*
X1259575Y509981D01*
G01X1263214Y512015D02*
X1259982D01*
G01X1263484Y510865D02*
X1260459D01*
G01X1272325Y525358D02*
Y522125D01*
G01X1273475Y524881D02*
Y522125D01*
G01X1274117Y527150D02*
X1272325Y525358D01*
G01X1274594Y526000D02*
X1273475Y524881D01*
G01X1282624Y527150D02*
X1274117D01*
G01X1282500Y526000D02*
X1274594D01*
G01X1273475Y524881D02*
Y522125D01*
G01X1272325Y525358D02*
Y522125D01*
G01X1274594Y526000D02*
X1273475Y524881D01*
G01X1274117Y527150D02*
X1272325Y525358D01*
G01X1282500Y526000D02*
X1274594D01*
G01X1282624Y527150D02*
X1274117D01*
G01X1270419Y510994D02*
X1282630D01*
G01X1270253Y512144D02*
X1282618D01*
G01X1270253D02*
X1282618D01*
G01X1270419Y510994D02*
X1282630D01*
G01X1263569Y963536D02*
X1258190D01*
G01X1263129Y964686D02*
X1258190D01*
G01X1263129D02*
X1258190D01*
G01X1263569Y963536D02*
X1258190D01*
G01X1282506Y979906D02*
X1274475D01*
G01X1282624Y978756D02*
X1274475D01*
G01X1282624D02*
X1274475D01*
G01X1282506Y979906D02*
X1274475D01*
G01X1269556Y963756D02*
X1282624D01*
G01X1269394Y964906D02*
X1282624D01*
G01X1269394D02*
X1282624D01*
G01X1269556Y963756D02*
X1282624D01*
G01X1383788Y57225D02*
Y54338D01*
G01X1382638Y57702D02*
Y54338D01*
G01X1384550Y57987D02*
X1383788Y57225D01*
G01X1384073Y59137D02*
X1382638Y57702D01*
G01X1387819Y57987D02*
X1384550D01*
G01X1387305Y59137D02*
X1384073D01*
G01X1382638Y57702D02*
Y54338D01*
G01X1383788Y57225D02*
Y54338D01*
G01X1384073Y59137D02*
X1382638Y57702D01*
G01X1384550Y57987D02*
X1383788Y57225D01*
G01X1387305Y59137D02*
X1384073D01*
G01X1387819Y57987D02*
X1384550D01*
G01X1396538Y72602D02*
Y69338D01*
G01X1397688Y72125D02*
Y69338D01*
G01X1398230Y74294D02*
X1396538Y72602D01*
G01X1398707Y73144D02*
X1397688Y72125D01*
G01X1406737Y74294D02*
X1398230D01*
G01X1406937Y73144D02*
X1398707D01*
G01X1397688Y72125D02*
Y69338D01*
G01X1396538Y72602D02*
Y69338D01*
G01X1398707Y73144D02*
X1397688Y72125D01*
G01X1398230Y74294D02*
X1396538Y72602D01*
G01X1406937Y73144D02*
X1398707D01*
G01X1406737Y74294D02*
X1398230D01*
G01X1393622Y58244D02*
X1406837D01*
G01X1393550Y59394D02*
X1406837D01*
G01X1393550D02*
X1406837D01*
G01X1393622Y58244D02*
X1406837D01*
G01X1383788Y509981D02*
Y507038D01*
G01X1382638Y510458D02*
Y507038D01*
G01X1384677Y510870D02*
X1383788Y509981D01*
G01X1384200Y512020D02*
X1382638Y510458D01*
G01X1387692Y510870D02*
X1384677D01*
G01X1387432Y512020D02*
X1384200D01*
G01X1382638Y510458D02*
Y507038D01*
G01X1383788Y509981D02*
Y507038D01*
G01X1384200Y512020D02*
X1382638Y510458D01*
G01X1384677Y510870D02*
X1383788Y509981D01*
G01X1387432Y512020D02*
X1384200D01*
G01X1387692Y510870D02*
X1384677D01*
G01X1396538Y525358D02*
Y522138D01*
G01X1397688Y524881D02*
Y522138D01*
G01X1398318Y527138D02*
X1396538Y525358D01*
G01X1398795Y525988D02*
X1397688Y524881D01*
G01X1406938Y527138D02*
X1398318D01*
G01X1406849Y525988D02*
X1398795D01*
G01X1397688Y524881D02*
Y522138D01*
G01X1396538Y525358D02*
Y522138D01*
G01X1398795Y525988D02*
X1397688Y524881D01*
G01X1398318Y527138D02*
X1396538Y525358D01*
G01X1406849Y525988D02*
X1398795D01*
G01X1406938Y527138D02*
X1398318D01*
G01X1394025Y511000D02*
X1406837D01*
G01X1393800Y512150D02*
X1406837D01*
G01X1393800D02*
X1406837D01*
G01X1394025Y511000D02*
X1406837D01*
G01X1387762Y963556D02*
X1382350D01*
G01X1387362Y964706D02*
X1382350D01*
G01X1387362D02*
X1382350D01*
G01X1387762Y963556D02*
X1382350D01*
G01X1406706Y979906D02*
X1398688D01*
G01X1406837Y978756D02*
X1398688D01*
G01X1406837D02*
X1398688D01*
G01X1406706Y979906D02*
X1398688D01*
G01X1393556Y963756D02*
X1406837D01*
G01X1393594Y964906D02*
X1406837D01*
G01X1393594D02*
X1406837D01*
G01X1393556Y963756D02*
X1406837D01*
G01X1508000Y57225D02*
Y54250D01*
G01X1506850Y57702D02*
Y54250D01*
G01X1508669Y57894D02*
X1508000Y57225D01*
G01X1508192Y59044D02*
X1506850Y57702D01*
G01X1512124Y57894D02*
X1508669D01*
G01X1511424Y59044D02*
X1508192D01*
G01X1506850Y57702D02*
Y54250D01*
G01X1508000Y57225D02*
Y54250D01*
G01X1508192Y59044D02*
X1506850Y57702D01*
G01X1508669Y57894D02*
X1508000Y57225D01*
G01X1511424Y59044D02*
X1508192D01*
G01X1512124Y57894D02*
X1508669D01*
G01X1520750Y72602D02*
Y69288D01*
G01X1521900Y72125D02*
Y69288D01*
G01X1522542Y74394D02*
X1520750Y72602D01*
G01X1523019Y73244D02*
X1521900Y72125D01*
G01X1531094Y74394D02*
X1522542D01*
G01X1531049Y73244D02*
X1523019D01*
G01X1521900Y72125D02*
Y69288D01*
G01X1520750Y72602D02*
Y69288D01*
G01X1523019Y73244D02*
X1521900Y72125D01*
G01X1522542Y74394D02*
X1520750Y72602D01*
G01X1531049Y73244D02*
X1523019D01*
G01X1531094Y74394D02*
X1522542D01*
G01X1517777Y58244D02*
X1531049D01*
G01X1517875Y59394D02*
X1531049D01*
G01X1517875D02*
X1531049D01*
G01X1517777Y58244D02*
X1531049D01*
G01X1508000Y509981D02*
Y507050D01*
G01X1506850Y510458D02*
Y507050D01*
G01X1508905Y510886D02*
X1508000Y509981D01*
G01X1508428Y512036D02*
X1506850Y510458D01*
G01X1511888Y510886D02*
X1508905D01*
G01X1511660Y512036D02*
X1508428D01*
G01X1506850Y510458D02*
Y507050D01*
G01X1508000Y509981D02*
Y507050D01*
G01X1508428Y512036D02*
X1506850Y510458D01*
G01X1508905Y510886D02*
X1508000Y509981D01*
G01X1511660Y512036D02*
X1508428D01*
G01X1511888Y510886D02*
X1508905D01*
G01X1520750Y525358D02*
Y522050D01*
G01X1521900Y524881D02*
Y522050D01*
G01X1522452Y527060D02*
X1520750Y525358D01*
G01X1522929Y525910D02*
X1521900Y524881D01*
G01X1530959Y527060D02*
X1522452D01*
G01X1531139Y525910D02*
X1522929D01*
G01X1521900Y524881D02*
Y522050D01*
G01X1520750Y525358D02*
Y522050D01*
G01X1522929Y525910D02*
X1521900Y524881D01*
G01X1522452Y527060D02*
X1520750Y525358D01*
G01X1531139Y525910D02*
X1522929D01*
G01X1530959Y527060D02*
X1522452D01*
G01X1517790Y511000D02*
X1531049D01*
G01X1517761Y512150D02*
X1531049D01*
G01X1517761D02*
X1531049D01*
G01X1517790Y511000D02*
X1531049D01*
G01X1512034Y963496D02*
X1506650D01*
G01X1511514Y964646D02*
X1506650D01*
G01X1511514D02*
X1506650D01*
G01X1512034Y963496D02*
X1506650D01*
G01X1531006Y979906D02*
X1522900D01*
G01X1531049Y978756D02*
X1522900D01*
G01X1531049D02*
X1522900D01*
G01X1531006Y979906D02*
X1522900D01*
G01X1517856Y963756D02*
X1531049D01*
G01X1517794Y964906D02*
X1531049D01*
G01X1517794D02*
X1531049D01*
G01X1517856Y963756D02*
X1531049D01*
G01X1632213Y57225D02*
Y54263D01*
G01X1631063Y57702D02*
Y54263D01*
G01X1633032Y58044D02*
X1632213Y57225D01*
G01X1632555Y59194D02*
X1631063Y57702D01*
G01X1636187Y58044D02*
X1633032D01*
G01X1635787Y59194D02*
X1632555D01*
G01X1631063Y57702D02*
Y54263D01*
G01X1632213Y57225D02*
Y54263D01*
G01X1632555Y59194D02*
X1631063Y57702D01*
G01X1633032Y58044D02*
X1632213Y57225D01*
G01X1635787Y59194D02*
X1632555D01*
G01X1636187Y58044D02*
X1633032D01*
G01X1644963Y72390D02*
Y69288D01*
G01X1646113Y71913D02*
Y69288D01*
G01X1646867Y74294D02*
X1644963Y72390D01*
G01X1647344Y73144D02*
X1646113Y71913D01*
G01X1655162Y74294D02*
X1646867D01*
G01X1655362Y73144D02*
X1647344D01*
G01X1646113Y71913D02*
Y69288D01*
G01X1644963Y72390D02*
Y69288D01*
G01X1647344Y73144D02*
X1646113Y71913D01*
G01X1646867Y74294D02*
X1644963Y72390D01*
G01X1655362Y73144D02*
X1647344D01*
G01X1655162Y74294D02*
X1646867D01*
G01X1641944Y58244D02*
X1655262D01*
G01X1642006Y59394D02*
X1655262D01*
G01X1642006D02*
X1655262D01*
G01X1641944Y58244D02*
X1655262D01*
G01X1632213Y509981D02*
Y506963D01*
G01X1631063Y510458D02*
Y506963D01*
G01X1633102Y510870D02*
X1632213Y509981D01*
G01X1632625Y512020D02*
X1631063Y510458D01*
G01X1636117Y510870D02*
X1633102D01*
G01X1635857Y512020D02*
X1632625D01*
G01X1631063Y510458D02*
Y506963D01*
G01X1632213Y509981D02*
Y506963D01*
G01X1632625Y512020D02*
X1631063Y510458D01*
G01X1633102Y510870D02*
X1632213Y509981D01*
G01X1635857Y512020D02*
X1632625D01*
G01X1636117Y510870D02*
X1633102D01*
G01X1644963Y525358D02*
Y522000D01*
G01X1646113Y524881D02*
Y522000D01*
G01X1646645Y527040D02*
X1644963Y525358D01*
G01X1647122Y525890D02*
X1646113Y524881D01*
G01X1655240Y527040D02*
X1646645D01*
G01X1655372Y525890D02*
X1647122D01*
G01X1646113Y524881D02*
Y522000D01*
G01X1644963Y525358D02*
Y522000D01*
G01X1647122Y525890D02*
X1646113Y524881D01*
G01X1646645Y527040D02*
X1644963Y525358D01*
G01X1655372Y525890D02*
X1647122D01*
G01X1655240Y527040D02*
X1646645D01*
G01X1641972Y511000D02*
X1655262D01*
G01X1641979Y512150D02*
X1655262D01*
G01X1641979D02*
X1655262D01*
G01X1641972Y511000D02*
X1655262D01*
G01X1635476Y964056D02*
X1630744D01*
G01X1636138Y965206D02*
X1630744D01*
G01X1636138D02*
X1630744D01*
G01X1635476Y964056D02*
X1630744D01*
G01X1655206Y979906D02*
X1647113D01*
G01X1655344Y978756D02*
X1647113D01*
G01X1655344D02*
X1647113D01*
G01X1655206Y979906D02*
X1647113D01*
G01X1642056Y963756D02*
X1655262D01*
G01X1641994Y964906D02*
X1655262D01*
G01X1641994D02*
X1655262D01*
G01X1642056Y963756D02*
X1655262D01*
G01X1756425Y57225D02*
Y54275D01*
G01X1755275Y57702D02*
Y54275D01*
G01X1757144Y57944D02*
X1756425Y57225D01*
G01X1756667Y59094D02*
X1755275Y57702D01*
G01X1760499Y57944D02*
X1757144D01*
G01X1759899Y59094D02*
X1756667D01*
G01X1755275Y57702D02*
Y54275D01*
G01X1756425Y57225D02*
Y54275D01*
G01X1756667Y59094D02*
X1755275Y57702D01*
G01X1757144Y57944D02*
X1756425Y57225D01*
G01X1759899Y59094D02*
X1756667D01*
G01X1760499Y57944D02*
X1757144D01*
G01X1769175Y72602D02*
Y69288D01*
G01X1770325Y72125D02*
Y69288D01*
G01X1770867Y74294D02*
X1769175Y72602D01*
G01X1771344Y73144D02*
X1770325Y72125D01*
G01X1779494Y74294D02*
X1770867D01*
G01X1779574Y73144D02*
X1771344D01*
G01X1770325Y72125D02*
Y69288D01*
G01X1769175Y72602D02*
Y69288D01*
G01X1771344Y73144D02*
X1770325Y72125D01*
G01X1770867Y74294D02*
X1769175Y72602D01*
G01X1779574Y73144D02*
X1771344D01*
G01X1779494Y74294D02*
X1770867D01*
G01X1766372Y58244D02*
X1779474D01*
G01X1766454Y59394D02*
X1779474D01*
G01X1766454D02*
X1779474D01*
G01X1766372Y58244D02*
X1779474D01*
G01X1756425Y509981D02*
Y507075D01*
G01X1755275Y510458D02*
Y507075D01*
G01X1757264Y510820D02*
X1756425Y509981D01*
G01X1756787Y511970D02*
X1755275Y510458D01*
G01X1760379Y510820D02*
X1757264D01*
G01X1760019Y511970D02*
X1756787D01*
G01X1755275Y510458D02*
Y507075D01*
G01X1756425Y509981D02*
Y507075D01*
G01X1756787Y511970D02*
X1755275Y510458D01*
G01X1757264Y510820D02*
X1756425Y509981D01*
G01X1760019Y511970D02*
X1756787D01*
G01X1760379Y510820D02*
X1757264D01*
G01X1769175Y525358D02*
Y522075D01*
G01X1770325Y524881D02*
Y522075D01*
G01X1770877Y527060D02*
X1769175Y525358D01*
G01X1771354Y525910D02*
X1770325Y524881D01*
G01X1779384Y527060D02*
X1770877D01*
G01X1779564Y525910D02*
X1771354D01*
G01X1770325Y524881D02*
Y522075D01*
G01X1769175Y525358D02*
Y522075D01*
G01X1771354Y525910D02*
X1770325Y524881D01*
G01X1770877Y527060D02*
X1769175Y525358D01*
G01X1779564Y525910D02*
X1771354D01*
G01X1779384Y527060D02*
X1770877D01*
G01X1766156Y511000D02*
X1779474D01*
G01X1766242Y512150D02*
X1779474D01*
G01X1766242D02*
X1779474D01*
G01X1766156Y511000D02*
X1779474D01*
G01X1760300Y963536D02*
X1755090D01*
G01X1759842Y964686D02*
X1755090D01*
G01X1759842D02*
X1755090D01*
G01X1760300Y963536D02*
X1755090D01*
G01X1779474Y979906D02*
X1771325D01*
G01X1779644Y978756D02*
X1771325D01*
G01X1779644D02*
X1771325D01*
G01X1779474Y979906D02*
X1771325D01*
G01X1766156Y963756D02*
X1779474D01*
G01X1766194Y964906D02*
X1779474D01*
G01X1766194D02*
X1779474D01*
G01X1766156Y963756D02*
X1779474D01*
G01X1880638Y57225D02*
Y54300D01*
G01X1879488Y57702D02*
Y54300D01*
G01X1881447Y58034D02*
X1880638Y57225D01*
G01X1880970Y59184D02*
X1879488Y57702D01*
G01X1884622Y58034D02*
X1881447D01*
G01X1884202Y59184D02*
X1880970D01*
G01X1879488Y57702D02*
Y54300D01*
G01X1880638Y57225D02*
Y54300D01*
G01X1880970Y59184D02*
X1879488Y57702D01*
G01X1881447Y58034D02*
X1880638Y57225D01*
G01X1884202Y59184D02*
X1880970D01*
G01X1884622Y58034D02*
X1881447D01*
G01X1893388Y72602D02*
Y69288D01*
G01X1894538Y72125D02*
Y69362D01*
G01X1894980Y74194D02*
X1893388Y72602D01*
G01X1895457Y73044D02*
X1894538Y72125D01*
G01X1903487Y74194D02*
X1894980D01*
G01X1903887Y73044D02*
X1895457D01*
G01X1894538Y72125D02*
Y69362D01*
G01X1893388Y72602D02*
Y69288D01*
G01X1895457Y73044D02*
X1894538Y72125D01*
G01X1894980Y74194D02*
X1893388Y72602D01*
G01X1903887Y73044D02*
X1895457D01*
G01X1903487Y74194D02*
X1894980D01*
G01X1890572Y58244D02*
X1903687D01*
G01X1890574Y59394D02*
X1903687D01*
G01X1890574D02*
X1903687D01*
G01X1890572Y58244D02*
X1903687D01*
G01X1880638Y509728D02*
Y507056D01*
G01X1879488Y510205D02*
Y507056D01*
G01X1881846Y510936D02*
X1880638Y509728D01*
G01X1881369Y512086D02*
X1879488Y510205D01*
G01X1884476Y510936D02*
X1881846D01*
G01X1884348Y512086D02*
X1881369D01*
G01X1879488Y510205D02*
Y507056D01*
G01X1880638Y509728D02*
Y507056D01*
G01X1881369Y512086D02*
X1879488Y510205D01*
G01X1881846Y510936D02*
X1880638Y509728D01*
G01X1884348Y512086D02*
X1881369D01*
G01X1884476Y510936D02*
X1881846D01*
G01X1893388Y525358D02*
Y522044D01*
G01X1894538Y524881D02*
Y522044D01*
G01X1895060Y527030D02*
X1893388Y525358D01*
G01X1895537Y525880D02*
X1894538Y524881D01*
G01X1903630Y527030D02*
X1895060D01*
G01X1903807Y525880D02*
X1895537D01*
G01X1894538Y524881D02*
Y522044D01*
G01X1893388Y525358D02*
Y522044D01*
G01X1895537Y525880D02*
X1894538Y524881D01*
G01X1895060Y527030D02*
X1893388Y525358D01*
G01X1903807Y525880D02*
X1895537D01*
G01X1903630Y527030D02*
X1895060D01*
G01X1890392Y511000D02*
X1903687D01*
G01X1890591Y512150D02*
X1903687D01*
G01X1890591D02*
X1903687D01*
G01X1890392Y511000D02*
X1903687D01*
G01X1884632Y963536D02*
X1879284D01*
G01X1884192Y964686D02*
X1879284D01*
G01X1884192D02*
X1879284D01*
G01X1884632Y963536D02*
X1879284D01*
G01X1903687Y979906D02*
X1895700D01*
G01X1903687Y978756D02*
X1895700D01*
G01X1903687D02*
X1895700D01*
G01X1903687Y979906D02*
X1895700D01*
G01X1890556Y963756D02*
X1903687D01*
G01X1890694Y964906D02*
X1903687D01*
G01X1890694D02*
X1903687D01*
G01X1890556Y963756D02*
X1903687D01*
G54D12*
G01X6250Y-33194D02*
Y-50694D01*
G01X1228Y-33194D02*
X11272D01*
G01X20038Y-50694D02*
Y-33194D01*
G01Y-41652D02*
X21130Y-40194D01*
X22222Y-39319D01*
X23968Y-39028D01*
X25278Y-39319D01*
X26807Y-40486D01*
X27462Y-42236D01*
Y-50694D01*
G01X41250Y-39028D02*
Y-50694D01*
G01Y-34361D02*
X40813Y-34069D01*
Y-33486D01*
X41250Y-33194D01*
X41687Y-33486D01*
Y-34069D01*
X41250Y-34361D01*
G01X55475Y-48653D02*
X56567Y-49819D01*
X58095Y-50694D01*
X59405D01*
X60715Y-50111D01*
X61588Y-49236D01*
X62025Y-48070D01*
X61807Y-46319D01*
X60933Y-45444D01*
X57003Y-43694D01*
X56130Y-41652D01*
X56567Y-40194D01*
X57440Y-39319D01*
X58750Y-39028D01*
X60060Y-39319D01*
X61370Y-40194D01*
G01X90693Y-55069D02*
X92222Y-56236D01*
X93968Y-56527D01*
X95496Y-56236D01*
X96807Y-54778D01*
X97680Y-52736D01*
Y-39028D01*
G01Y-41361D02*
X96807Y-40194D01*
X95496Y-39319D01*
X93968Y-39028D01*
X92222Y-39611D01*
X91130Y-40777D01*
X90256Y-42819D01*
X89820Y-44861D01*
X90038Y-46611D01*
X90912Y-48653D01*
X92222Y-50111D01*
X93968Y-50694D01*
X95278Y-50402D01*
X96807Y-49236D01*
X97680Y-48070D01*
G01X107975Y-42819D02*
X114962D01*
X114307Y-40777D01*
X113215Y-39611D01*
X111687Y-39028D01*
X110158Y-39319D01*
X108848Y-40194D01*
X107975Y-42236D01*
X107538Y-43986D01*
Y-45736D01*
X107975Y-47486D01*
X109067Y-49236D01*
X110377Y-50402D01*
X111905Y-50694D01*
X113433Y-50111D01*
X114962Y-48361D01*
G01X125693Y-50694D02*
Y-39028D01*
G01Y-41361D02*
X126785Y-40194D01*
X127877Y-39319D01*
X129405Y-39028D01*
X130496Y-39319D01*
X131807Y-40194D01*
G01X142320Y-50694D02*
Y-33194D01*
G01Y-41944D02*
X143412Y-40194D01*
X144722Y-39319D01*
X146032Y-39028D01*
X147996Y-39611D01*
X149307Y-40777D01*
X150180Y-42819D01*
Y-45152D01*
X149743Y-47486D01*
X148870Y-49236D01*
X147342Y-50402D01*
X146032Y-50694D01*
X144722Y-50402D01*
X143412Y-49528D01*
X142320Y-48070D01*
G01X160475Y-42819D02*
X167462D01*
X166807Y-40777D01*
X165715Y-39611D01*
X164187Y-39028D01*
X162658Y-39319D01*
X161348Y-40194D01*
X160475Y-42236D01*
X160038Y-43986D01*
Y-45736D01*
X160475Y-47486D01*
X161567Y-49236D01*
X162877Y-50402D01*
X164405Y-50694D01*
X165933Y-50111D01*
X167462Y-48361D01*
G01X178193Y-50694D02*
Y-39028D01*
G01Y-41361D02*
X179285Y-40194D01*
X180377Y-39319D01*
X181905Y-39028D01*
X182996Y-39319D01*
X184307Y-40194D01*
G01X216250Y-39028D02*
Y-50694D01*
G01Y-34361D02*
X215813Y-34069D01*
Y-33486D01*
X216250Y-33194D01*
X216687Y-33486D01*
Y-34069D01*
X216250Y-34361D01*
G01X230475Y-48653D02*
X231567Y-49819D01*
X233095Y-50694D01*
X234405D01*
X235715Y-50111D01*
X236588Y-49236D01*
X237025Y-48070D01*
X236807Y-46319D01*
X235933Y-45444D01*
X232003Y-43694D01*
X231130Y-41652D01*
X231567Y-40194D01*
X232440Y-39319D01*
X233750Y-39028D01*
X235060Y-39319D01*
X236370Y-40194D01*
G01X265256Y-55069D02*
X266785Y-56236D01*
X268095Y-56527D01*
X269842Y-55944D01*
X271152Y-54486D01*
X271807Y-51860D01*
Y-39028D01*
G01Y-34361D02*
X271370Y-34069D01*
Y-33486D01*
X271807Y-33194D01*
X272243Y-33486D01*
Y-34069D01*
X271807Y-34361D01*
G01X282538Y-39028D02*
Y-47194D01*
X283412Y-49236D01*
X284722Y-50402D01*
X286250Y-50694D01*
X287778Y-50402D01*
X289088Y-49236D01*
X289962Y-47194D01*
G01Y-50694D02*
Y-39028D01*
G01X300475Y-48653D02*
X301567Y-49819D01*
X303095Y-50694D01*
X304405D01*
X305715Y-50111D01*
X306588Y-49236D01*
X307025Y-48070D01*
X306807Y-46319D01*
X305933Y-45444D01*
X302003Y-43694D01*
X301130Y-41652D01*
X301567Y-40194D01*
X302440Y-39319D01*
X303750Y-39028D01*
X305060Y-39319D01*
X306370Y-40194D01*
G01X321250Y-33194D02*
Y-50694D01*
G01X318193Y-39028D02*
X324307D01*
G01X354940Y-50694D02*
Y-35819D01*
X355377Y-34361D01*
X356250Y-33486D01*
X357560Y-33194D01*
X358870Y-33777D01*
X359525Y-35236D01*
G01X356905Y-40194D02*
X352538D01*
G01X373750Y-50694D02*
X372440Y-50402D01*
X371130Y-49236D01*
X370256Y-47194D01*
X369820Y-44861D01*
X370256Y-42527D01*
X371130Y-40486D01*
X372440Y-39319D01*
X373750Y-39028D01*
X375060Y-39319D01*
X376370Y-40486D01*
X377243Y-42527D01*
X377462Y-44861D01*
X377243Y-47194D01*
X376370Y-49236D01*
X375060Y-50402D01*
X373750Y-50694D01*
G01X388193D02*
Y-39028D01*
G01Y-41361D02*
X389285Y-40194D01*
X390377Y-39319D01*
X391905Y-39028D01*
X392996Y-39319D01*
X394307Y-40194D01*
G01X421665Y-55944D02*
X422975Y-56527D01*
X424722Y-55944D01*
X425813Y-54778D01*
X426687Y-53319D01*
X427996Y-48653D01*
X430835Y-39028D01*
G01X423848D02*
X427996Y-48653D01*
G01X443750Y-50694D02*
X442440Y-50402D01*
X441130Y-49236D01*
X440256Y-47194D01*
X439820Y-44861D01*
X440256Y-42527D01*
X441130Y-40486D01*
X442440Y-39319D01*
X443750Y-39028D01*
X445060Y-39319D01*
X446370Y-40486D01*
X447243Y-42527D01*
X447462Y-44861D01*
X447243Y-47194D01*
X446370Y-49236D01*
X445060Y-50402D01*
X443750Y-50694D01*
G01X457538Y-39028D02*
Y-47194D01*
X458412Y-49236D01*
X459722Y-50402D01*
X461250Y-50694D01*
X462778Y-50402D01*
X464088Y-49236D01*
X464962Y-47194D01*
G01Y-50694D02*
Y-39028D01*
G01X475693Y-50694D02*
Y-39028D01*
G01Y-41361D02*
X476785Y-40194D01*
X477877Y-39319D01*
X479405Y-39028D01*
X480496Y-39319D01*
X481807Y-40194D01*
G01X510693Y-50694D02*
Y-39028D01*
G01Y-41361D02*
X511785Y-40194D01*
X512877Y-39319D01*
X514405Y-39028D01*
X515496Y-39319D01*
X516807Y-40194D01*
G01X527975Y-42819D02*
X534962D01*
X534307Y-40777D01*
X533215Y-39611D01*
X531687Y-39028D01*
X530158Y-39319D01*
X528848Y-40194D01*
X527975Y-42236D01*
X527538Y-43986D01*
Y-45736D01*
X527975Y-47486D01*
X529067Y-49236D01*
X530377Y-50402D01*
X531905Y-50694D01*
X533433Y-50111D01*
X534962Y-48361D01*
G01X547440Y-50694D02*
Y-35819D01*
X547877Y-34361D01*
X548750Y-33486D01*
X550060Y-33194D01*
X551370Y-33777D01*
X552025Y-35236D01*
G01X549405Y-40194D02*
X545038D01*
G01X562975Y-42819D02*
X569962D01*
X569307Y-40777D01*
X568215Y-39611D01*
X566687Y-39028D01*
X565158Y-39319D01*
X563848Y-40194D01*
X562975Y-42236D01*
X562538Y-43986D01*
Y-45736D01*
X562975Y-47486D01*
X564067Y-49236D01*
X565377Y-50402D01*
X566905Y-50694D01*
X568433Y-50111D01*
X569962Y-48361D01*
G01X580693Y-50694D02*
Y-39028D01*
G01Y-41361D02*
X581785Y-40194D01*
X582877Y-39319D01*
X584405Y-39028D01*
X585496Y-39319D01*
X586807Y-40194D01*
G01X597975Y-42819D02*
X604962D01*
X604307Y-40777D01*
X603215Y-39611D01*
X601687Y-39028D01*
X600158Y-39319D01*
X598848Y-40194D01*
X597975Y-42236D01*
X597538Y-43986D01*
Y-45736D01*
X597975Y-47486D01*
X599067Y-49236D01*
X600377Y-50402D01*
X601905Y-50694D01*
X603433Y-50111D01*
X604962Y-48361D01*
G01X615038Y-50694D02*
Y-39028D01*
G01Y-41944D02*
X615912Y-40486D01*
X617222Y-39319D01*
X618968Y-39028D01*
X620496Y-39319D01*
X621807Y-40486D01*
X622462Y-42527D01*
Y-50694D01*
G01X639743Y-40486D02*
X638215Y-39319D01*
X636905Y-39028D01*
X635158Y-39611D01*
X633848Y-40777D01*
X632975Y-42819D01*
X632756Y-44861D01*
X632975Y-46903D01*
X633848Y-48653D01*
X635158Y-50111D01*
X636905Y-50694D01*
X638433Y-50111D01*
X639743Y-48944D01*
G01X650475Y-42819D02*
X657462D01*
X656807Y-40777D01*
X655715Y-39611D01*
X654187Y-39028D01*
X652658Y-39319D01*
X651348Y-40194D01*
X650475Y-42236D01*
X650038Y-43986D01*
Y-45736D01*
X650475Y-47486D01*
X651567Y-49236D01*
X652877Y-50402D01*
X654405Y-50694D01*
X655933Y-50111D01*
X657462Y-48361D01*
G01X688750Y-33194D02*
Y-50694D01*
G01X685693Y-39028D02*
X691807D01*
G01X706250Y-50694D02*
X704940Y-50402D01*
X703630Y-49236D01*
X702756Y-47194D01*
X702320Y-44861D01*
X702756Y-42527D01*
X703630Y-40486D01*
X704940Y-39319D01*
X706250Y-39028D01*
X707560Y-39319D01*
X708870Y-40486D01*
X709743Y-42527D01*
X709962Y-44861D01*
X709743Y-47194D01*
X708870Y-49236D01*
X707560Y-50402D01*
X706250Y-50694D01*
G01X739940D02*
Y-35819D01*
X740377Y-34361D01*
X741250Y-33486D01*
X742560Y-33194D01*
X743870Y-33777D01*
X744525Y-35236D01*
G01X741905Y-40194D02*
X737538D01*
G01X758750Y-39028D02*
Y-50694D01*
G01Y-34361D02*
X758313Y-34069D01*
Y-33486D01*
X758750Y-33194D01*
X759187Y-33486D01*
Y-34069D01*
X758750Y-34361D01*
G01X772538Y-50694D02*
Y-39028D01*
G01Y-41944D02*
X773412Y-40486D01*
X774722Y-39319D01*
X776468Y-39028D01*
X777996Y-39319D01*
X779307Y-40486D01*
X779962Y-42527D01*
Y-50694D01*
G01X797680Y-33194D02*
Y-50694D01*
G01Y-48070D02*
X796807Y-49528D01*
X795496Y-50402D01*
X793968Y-50694D01*
X792222Y-50111D01*
X790912Y-48653D01*
X790038Y-46903D01*
X789820Y-44861D01*
X790038Y-42819D01*
X790912Y-41069D01*
X792222Y-39611D01*
X793968Y-39028D01*
X795496Y-39319D01*
X796588Y-39903D01*
X797680Y-41069D01*
G01X828750Y-33194D02*
Y-50694D01*
G01X825693Y-39028D02*
X831807D01*
G01X842538Y-50694D02*
Y-33194D01*
G01Y-41652D02*
X843630Y-40194D01*
X844722Y-39319D01*
X846468Y-39028D01*
X847778Y-39319D01*
X849307Y-40486D01*
X849962Y-42236D01*
Y-50694D01*
G01X860475Y-42819D02*
X867462D01*
X866807Y-40777D01*
X865715Y-39611D01*
X864187Y-39028D01*
X862658Y-39319D01*
X861348Y-40194D01*
X860475Y-42236D01*
X860038Y-43986D01*
Y-45736D01*
X860475Y-47486D01*
X861567Y-49236D01*
X862877Y-50402D01*
X864405Y-50694D01*
X865933Y-50111D01*
X867462Y-48361D01*
G01X893947Y-50694D02*
Y-33194D01*
X898313D01*
X900060Y-34069D01*
X901370Y-35236D01*
X902462Y-36985D01*
X903335Y-39028D01*
X903553Y-41944D01*
X903335Y-44861D01*
X902462Y-46903D01*
X901370Y-48653D01*
X900060Y-49819D01*
X898313Y-50694D01*
X893947D01*
G01X911883D02*
Y-33194D01*
X917123D01*
X918870Y-34069D01*
X920180Y-36111D01*
X920617Y-38444D01*
X920180Y-40777D01*
X919088Y-42527D01*
X917123Y-43403D01*
X911883D01*
G01X951250Y-39028D02*
Y-50694D01*
G01Y-34361D02*
X950813Y-34069D01*
Y-33486D01*
X951250Y-33194D01*
X951687Y-33486D01*
Y-34069D01*
X951250Y-34361D01*
G01X962200Y-50694D02*
Y-39028D01*
G01Y-42236D02*
X962855Y-40777D01*
X963947Y-39611D01*
X965475Y-39028D01*
X967003Y-39611D01*
X968095Y-40777D01*
X968750Y-42236D01*
Y-50694D01*
G01Y-42236D02*
X969405Y-40777D01*
X970496Y-39611D01*
X972025Y-39028D01*
X973553Y-39611D01*
X974645Y-40777D01*
X975300Y-42527D01*
Y-50694D01*
G01X982320Y-56527D02*
Y-39028D01*
G01Y-41652D02*
X983412Y-40194D01*
X984503Y-39319D01*
X986250Y-39028D01*
X987778Y-39319D01*
X989307Y-40777D01*
X989962Y-42819D01*
X990180Y-44861D01*
X989962Y-46903D01*
X989307Y-48944D01*
X987996Y-50111D01*
X986250Y-50694D01*
X984722Y-50402D01*
X983193Y-49528D01*
X982320Y-48361D01*
G01X1000475Y-42819D02*
X1007462D01*
X1006807Y-40777D01*
X1005715Y-39611D01*
X1004187Y-39028D01*
X1002658Y-39319D01*
X1001348Y-40194D01*
X1000475Y-42236D01*
X1000038Y-43986D01*
Y-45736D01*
X1000475Y-47486D01*
X1001567Y-49236D01*
X1002877Y-50402D01*
X1004405Y-50694D01*
X1005933Y-50111D01*
X1007462Y-48361D01*
G01X1025180Y-33194D02*
Y-50694D01*
G01Y-48070D02*
X1024307Y-49528D01*
X1022996Y-50402D01*
X1021468Y-50694D01*
X1019722Y-50111D01*
X1018412Y-48653D01*
X1017538Y-46903D01*
X1017320Y-44861D01*
X1017538Y-42819D01*
X1018412Y-41069D01*
X1019722Y-39611D01*
X1021468Y-39028D01*
X1022996Y-39319D01*
X1024088Y-39903D01*
X1025180Y-41069D01*
G01X1042680Y-50694D02*
Y-39028D01*
G01Y-41069D02*
X1041807Y-39903D01*
X1040496Y-39319D01*
X1038968Y-39028D01*
X1037440Y-39611D01*
X1036130Y-40777D01*
X1035256Y-42527D01*
X1034820Y-44861D01*
X1035256Y-47194D01*
X1036130Y-48944D01*
X1037440Y-50111D01*
X1038968Y-50694D01*
X1040496Y-50402D01*
X1041807Y-49528D01*
X1042680Y-48361D01*
G01X1052538Y-50694D02*
Y-39028D01*
G01Y-41944D02*
X1053412Y-40486D01*
X1054722Y-39319D01*
X1056468Y-39028D01*
X1057996Y-39319D01*
X1059307Y-40486D01*
X1059962Y-42527D01*
Y-50694D01*
G01X1077243Y-40486D02*
X1075715Y-39319D01*
X1074405Y-39028D01*
X1072658Y-39611D01*
X1071348Y-40777D01*
X1070475Y-42819D01*
X1070256Y-44861D01*
X1070475Y-46903D01*
X1071348Y-48653D01*
X1072658Y-50111D01*
X1074405Y-50694D01*
X1075933Y-50111D01*
X1077243Y-48944D01*
G01X1087975Y-42819D02*
X1094962D01*
X1094307Y-40777D01*
X1093215Y-39611D01*
X1091687Y-39028D01*
X1090158Y-39319D01*
X1088848Y-40194D01*
X1087975Y-42236D01*
X1087538Y-43986D01*
Y-45736D01*
X1087975Y-47486D01*
X1089067Y-49236D01*
X1090377Y-50402D01*
X1091905Y-50694D01*
X1093433Y-50111D01*
X1094962Y-48361D01*
G01X1126250Y-33194D02*
Y-50694D01*
G01X1123193Y-39028D02*
X1129307D01*
G01X1140693Y-50694D02*
Y-39028D01*
G01Y-41361D02*
X1141785Y-40194D01*
X1142877Y-39319D01*
X1144405Y-39028D01*
X1145496Y-39319D01*
X1146807Y-40194D01*
G01X1165180Y-50694D02*
Y-39028D01*
G01Y-41069D02*
X1164307Y-39903D01*
X1162996Y-39319D01*
X1161468Y-39028D01*
X1159940Y-39611D01*
X1158630Y-40777D01*
X1157756Y-42527D01*
X1157320Y-44861D01*
X1157756Y-47194D01*
X1158630Y-48944D01*
X1159940Y-50111D01*
X1161468Y-50694D01*
X1162996Y-50402D01*
X1164307Y-49528D01*
X1165180Y-48361D01*
G01X1182243Y-40486D02*
X1180715Y-39319D01*
X1179405Y-39028D01*
X1177658Y-39611D01*
X1176348Y-40777D01*
X1175475Y-42819D01*
X1175256Y-44861D01*
X1175475Y-46903D01*
X1176348Y-48653D01*
X1177658Y-50111D01*
X1179405Y-50694D01*
X1180933Y-50111D01*
X1182243Y-48944D01*
G01X1192975Y-42819D02*
X1199962D01*
X1199307Y-40777D01*
X1198215Y-39611D01*
X1196687Y-39028D01*
X1195158Y-39319D01*
X1193848Y-40194D01*
X1192975Y-42236D01*
X1192538Y-43986D01*
Y-45736D01*
X1192975Y-47486D01*
X1194067Y-49236D01*
X1195377Y-50402D01*
X1196905Y-50694D01*
X1198433Y-50111D01*
X1199962Y-48361D01*
G01X1210475Y-48653D02*
X1211567Y-49819D01*
X1213095Y-50694D01*
X1214405D01*
X1215715Y-50111D01*
X1216588Y-49236D01*
X1217025Y-48070D01*
X1216807Y-46319D01*
X1215933Y-45444D01*
X1212003Y-43694D01*
X1211130Y-41652D01*
X1211567Y-40194D01*
X1212440Y-39319D01*
X1213750Y-39028D01*
X1215060Y-39319D01*
X1216370Y-40194D01*
G01X1248750Y-39028D02*
Y-50694D01*
G01Y-34361D02*
X1248313Y-34069D01*
Y-33486D01*
X1248750Y-33194D01*
X1249187Y-33486D01*
Y-34069D01*
X1248750Y-34361D01*
G01X1262538Y-50694D02*
Y-39028D01*
G01Y-41944D02*
X1263412Y-40486D01*
X1264722Y-39319D01*
X1266468Y-39028D01*
X1267996Y-39319D01*
X1269307Y-40486D01*
X1269962Y-42527D01*
Y-50694D01*
G01X1301250D02*
Y-33194D01*
G01X1322680Y-50694D02*
Y-39028D01*
G01Y-41069D02*
X1321807Y-39903D01*
X1320496Y-39319D01*
X1318968Y-39028D01*
X1317440Y-39611D01*
X1316130Y-40777D01*
X1315256Y-42527D01*
X1314820Y-44861D01*
X1315256Y-47194D01*
X1316130Y-48944D01*
X1317440Y-50111D01*
X1318968Y-50694D01*
X1320496Y-50402D01*
X1321807Y-49528D01*
X1322680Y-48361D01*
G01X1331665Y-55944D02*
X1332975Y-56527D01*
X1334722Y-55944D01*
X1335813Y-54778D01*
X1336687Y-53319D01*
X1337996Y-48653D01*
X1340835Y-39028D01*
G01X1333848D02*
X1337996Y-48653D01*
G01X1350475Y-42819D02*
X1357462D01*
X1356807Y-40777D01*
X1355715Y-39611D01*
X1354187Y-39028D01*
X1352658Y-39319D01*
X1351348Y-40194D01*
X1350475Y-42236D01*
X1350038Y-43986D01*
Y-45736D01*
X1350475Y-47486D01*
X1351567Y-49236D01*
X1352877Y-50402D01*
X1354405Y-50694D01*
X1355933Y-50111D01*
X1357462Y-48361D01*
G01X1368193Y-50694D02*
Y-39028D01*
G01Y-41361D02*
X1369285Y-40194D01*
X1370377Y-39319D01*
X1371905Y-39028D01*
X1372996Y-39319D01*
X1374307Y-40194D01*
G01X1401883Y-33194D02*
Y-50694D01*
X1410617D01*
G01X1423750D02*
Y-33194D01*
X1421130Y-36694D01*
G01Y-50694D02*
X1426370D01*
G01X1441250Y-51277D02*
X1440813Y-50986D01*
Y-50402D01*
X1441250Y-50111D01*
X1441687Y-50402D01*
Y-50986D01*
X1441250Y-51277D01*
G01X1986890Y1495085D02*
Y1512585D01*
X1991256D01*
X1993003Y1511710D01*
X1994313Y1510543D01*
X1995405Y1508794D01*
X1996278Y1506751D01*
X1996496Y1503835D01*
X1996278Y1500918D01*
X1995405Y1498876D01*
X1994313Y1497126D01*
X1993003Y1495960D01*
X1991256Y1495085D01*
X1986890D01*
G01X2004826D02*
Y1512585D01*
X2010066D01*
X2011813Y1511710D01*
X2013123Y1509668D01*
X2013560Y1507335D01*
X2013123Y1505002D01*
X2012031Y1503252D01*
X2010066Y1502376D01*
X2004826D01*
G01X2041573Y1512585D02*
X2046813D01*
G01X2044193D02*
Y1495085D01*
G01X2041573D02*
X2046813D01*
G01X2056016D02*
Y1512585D01*
X2061693Y1498002D01*
X2067370Y1512585D01*
Y1495085D01*
G01X2074826D02*
Y1512585D01*
X2080066D01*
X2081813Y1511710D01*
X2083123Y1509668D01*
X2083560Y1507335D01*
X2083123Y1505002D01*
X2082031Y1503252D01*
X2080066Y1502376D01*
X2074826D01*
G01X2101060Y1495085D02*
X2092326D01*
Y1512585D01*
X2101060D01*
G01X2097566Y1504127D02*
X2092326D01*
G01X2109390Y1495085D02*
Y1512585D01*
X2113756D01*
X2115503Y1511710D01*
X2116813Y1510543D01*
X2117905Y1508794D01*
X2118778Y1506751D01*
X2118996Y1503835D01*
X2118778Y1500918D01*
X2117905Y1498876D01*
X2116813Y1497126D01*
X2115503Y1495960D01*
X2113756Y1495085D01*
X2109390D01*
G01X2126234D02*
X2131693Y1512585D01*
X2137152Y1495085D01*
G01X2135186Y1501210D02*
X2128199D01*
G01X2144171Y1495085D02*
Y1512585D01*
X2154215Y1495085D01*
Y1512585D01*
G01X2171496Y1511126D02*
X2170186Y1512002D01*
X2168658Y1512585D01*
X2166911D01*
X2164946Y1511710D01*
X2163418Y1510252D01*
X2162326Y1508501D01*
X2161453Y1505585D01*
X2161234Y1502960D01*
X2161671Y1500335D01*
X2162326Y1498585D01*
X2163636Y1496835D01*
X2165165Y1495668D01*
X2166693Y1495085D01*
X2168221D01*
X2169750Y1495668D01*
X2171060Y1496543D01*
X2172152Y1497709D01*
G01X2188560Y1495085D02*
X2179826D01*
Y1512585D01*
X2188560D01*
G01X2185066Y1504127D02*
X2179826D01*
G01X2219193Y1512585D02*
Y1495085D01*
G01X2214171Y1512585D02*
X2224215D01*
G01X2231234Y1495085D02*
X2236693Y1512585D01*
X2242152Y1495085D01*
G01X2240186Y1501210D02*
X2233199D01*
G01X2255939Y1504418D02*
X2256813Y1505293D01*
X2257468Y1506751D01*
X2257905Y1508794D01*
X2257468Y1510543D01*
X2256595Y1511710D01*
X2255066Y1512585D01*
X2249171D01*
Y1495085D01*
X2256376D01*
X2257905Y1496251D01*
X2258778Y1498002D01*
X2259215Y1500043D01*
X2258778Y1502085D01*
X2257468Y1503835D01*
X2255939Y1504418D01*
X2249171D01*
G01X2267326Y1512585D02*
Y1495085D01*
X2276060D01*
G01X2293560D02*
X2284826D01*
Y1512585D01*
X2293560D01*
G01X2290066Y1504127D02*
X2284826D01*
G01X2306693Y1494502D02*
X2306256Y1494793D01*
Y1495377D01*
X2306693Y1495668D01*
X2307130Y1495377D01*
Y1494793D01*
X2306693Y1494502D01*
G01Y1502376D02*
X2306256Y1502668D01*
Y1503252D01*
X2306693Y1503543D01*
X2307130Y1503252D01*
Y1502668D01*
X2306693Y1502376D01*
G01X2337326Y1512585D02*
Y1495085D01*
X2346060D01*
G01X2359193D02*
Y1512585D01*
X2356573Y1509085D01*
G01Y1495085D02*
X2361813D01*
G01X2008773Y1477935D02*
X2014013D01*
G01X2011393D02*
Y1460435D01*
G01X2008773D02*
X2014013D01*
G01X2023216D02*
Y1477935D01*
X2028893Y1463352D01*
X2034570Y1477935D01*
Y1460435D01*
G01X2042026D02*
Y1477935D01*
X2047266D01*
X2049013Y1477060D01*
X2050323Y1475018D01*
X2050760Y1472685D01*
X2050323Y1470352D01*
X2049231Y1468602D01*
X2047266Y1467726D01*
X2042026D01*
G01X2062801Y1454602D02*
X2060618Y1457518D01*
X2059526Y1460435D01*
Y1472101D01*
X2060618Y1475018D01*
X2062801Y1477935D01*
G01X2081393Y1460435D02*
X2079646Y1460727D01*
X2078118Y1461893D01*
X2076808Y1463643D01*
X2075934Y1465685D01*
X2075498Y1468018D01*
Y1470352D01*
X2075934Y1472685D01*
X2076808Y1474727D01*
X2078118Y1476476D01*
X2079646Y1477643D01*
X2081393Y1477935D01*
X2083139Y1477643D01*
X2084668Y1476476D01*
X2085978Y1474727D01*
X2086852Y1472685D01*
X2087288Y1470352D01*
Y1468018D01*
X2086852Y1465685D01*
X2085978Y1463643D01*
X2084668Y1461893D01*
X2083139Y1460727D01*
X2081393Y1460435D01*
G01X2095181D02*
Y1477935D01*
G01Y1469477D02*
X2096273Y1470935D01*
X2097365Y1471810D01*
X2099111Y1472101D01*
X2100421Y1471810D01*
X2101950Y1470643D01*
X2102605Y1468893D01*
Y1460435D01*
G01X2109843D02*
Y1472101D01*
G01Y1468893D02*
X2110498Y1470352D01*
X2111590Y1471518D01*
X2113118Y1472101D01*
X2114646Y1471518D01*
X2115738Y1470352D01*
X2116393Y1468893D01*
Y1460435D01*
G01Y1468893D02*
X2117048Y1470352D01*
X2118139Y1471518D01*
X2119668Y1472101D01*
X2121196Y1471518D01*
X2122288Y1470352D01*
X2122943Y1468602D01*
Y1460435D01*
G01X2134985Y1454602D02*
X2137168Y1457518D01*
X2138260Y1460435D01*
Y1472101D01*
X2137168Y1475018D01*
X2134985Y1477935D01*
G01X2032840Y1425202D02*
X2042446Y1438035D01*
G01X2037643Y1440368D02*
Y1422868D01*
G01X2042446Y1425202D02*
X2032840Y1438035D01*
G01X2031093Y1431618D02*
X2044193D01*
G01X2055143Y1425785D02*
X2056671Y1426077D01*
X2058418Y1426951D01*
X2059510Y1428409D01*
X2059946Y1430452D01*
X2059510Y1432493D01*
X2058200Y1434243D01*
X2056235Y1435118D01*
X2054051D01*
X2052741Y1435702D01*
X2051649Y1437160D01*
X2051213Y1439201D01*
X2051868Y1441243D01*
X2053396Y1442702D01*
X2055143Y1443285D01*
X2056889Y1442702D01*
X2058418Y1441243D01*
X2059073Y1439201D01*
X2058636Y1437160D01*
X2057545Y1435702D01*
X2056235Y1435118D01*
X2054051D01*
X2052086Y1434243D01*
X2050776Y1432493D01*
X2050340Y1430452D01*
X2050776Y1428409D01*
X2051868Y1426951D01*
X2053615Y1426077D01*
X2055143Y1425785D01*
G01X2067840Y1428409D02*
X2069149Y1426951D01*
X2070678Y1426077D01*
X2072643Y1425785D01*
X2074608Y1426368D01*
X2076136Y1427535D01*
X2077228Y1429576D01*
X2077446Y1431910D01*
X2077010Y1434243D01*
X2075918Y1435702D01*
X2074389Y1436868D01*
X2072861Y1437160D01*
X2071333Y1436868D01*
X2069368Y1435702D01*
X2070023Y1443285D01*
X2075918D01*
G01X2090143Y1425202D02*
X2089706Y1425493D01*
Y1426077D01*
X2090143Y1426368D01*
X2090580Y1426077D01*
Y1425493D01*
X2090143Y1425202D01*
G01X2107643Y1443285D02*
X2105896Y1442702D01*
X2104586Y1441243D01*
X2103713Y1439494D01*
X2103058Y1437160D01*
X2102840Y1434535D01*
X2103058Y1431910D01*
X2103713Y1429576D01*
X2104586Y1427826D01*
X2105896Y1426368D01*
X2107643Y1425785D01*
X2109389Y1426368D01*
X2110700Y1427826D01*
X2111573Y1429576D01*
X2112228Y1431910D01*
X2112446Y1434535D01*
X2112228Y1437160D01*
X2111573Y1439494D01*
X2110700Y1441243D01*
X2109389Y1442702D01*
X2107643Y1443285D01*
G01X2037643Y1391135D02*
Y1408635D01*
X2035023Y1405135D01*
G01Y1391135D02*
X2040263D01*
G01X2055143Y1408635D02*
X2053396Y1408052D01*
X2052086Y1406593D01*
X2051213Y1404844D01*
X2050558Y1402510D01*
X2050340Y1399885D01*
X2050558Y1397260D01*
X2051213Y1394926D01*
X2052086Y1393176D01*
X2053396Y1391718D01*
X2055143Y1391135D01*
X2056889Y1391718D01*
X2058200Y1393176D01*
X2059073Y1394926D01*
X2059728Y1397260D01*
X2059946Y1399885D01*
X2059728Y1402510D01*
X2059073Y1404844D01*
X2058200Y1406593D01*
X2056889Y1408052D01*
X2055143Y1408635D01*
G01X2072643D02*
X2070896Y1408052D01*
X2069586Y1406593D01*
X2068713Y1404844D01*
X2068058Y1402510D01*
X2067840Y1399885D01*
X2068058Y1397260D01*
X2068713Y1394926D01*
X2069586Y1393176D01*
X2070896Y1391718D01*
X2072643Y1391135D01*
X2074389Y1391718D01*
X2075700Y1393176D01*
X2076573Y1394926D01*
X2077228Y1397260D01*
X2077446Y1399885D01*
X2077228Y1402510D01*
X2076573Y1404844D01*
X2075700Y1406593D01*
X2074389Y1408052D01*
X2072643Y1408635D01*
G01X2090143Y1390552D02*
X2089706Y1390843D01*
Y1391427D01*
X2090143Y1391718D01*
X2090580Y1391427D01*
Y1390843D01*
X2090143Y1390552D01*
G01X2107643Y1408635D02*
X2105896Y1408052D01*
X2104586Y1406593D01*
X2103713Y1404844D01*
X2103058Y1402510D01*
X2102840Y1399885D01*
X2103058Y1397260D01*
X2103713Y1394926D01*
X2104586Y1393176D01*
X2105896Y1391718D01*
X2107643Y1391135D01*
X2109389Y1391718D01*
X2110700Y1393176D01*
X2111573Y1394926D01*
X2112228Y1397260D01*
X2112446Y1399885D01*
X2112228Y1402510D01*
X2111573Y1404844D01*
X2110700Y1406593D01*
X2109389Y1408052D01*
X2107643Y1408635D01*
G01X2188593Y1477935D02*
X2191649Y1460435D01*
X2195143Y1477935D01*
X2198636Y1460435D01*
X2201693Y1477935D01*
G01X2210023D02*
X2215263D01*
G01X2212643D02*
Y1460435D01*
G01X2210023D02*
X2215263D01*
G01X2225340D02*
Y1477935D01*
X2229706D01*
X2231453Y1477060D01*
X2232763Y1475893D01*
X2233855Y1474144D01*
X2234728Y1472101D01*
X2234946Y1469185D01*
X2234728Y1466268D01*
X2233855Y1464226D01*
X2232763Y1462476D01*
X2231453Y1461310D01*
X2229706Y1460435D01*
X2225340D01*
G01X2247643Y1477935D02*
Y1460435D01*
G01X2242621Y1477935D02*
X2252665D01*
G01X2260558Y1460435D02*
Y1477935D01*
G01X2269728D02*
Y1460435D01*
G01Y1469185D02*
X2260558D01*
G01X2281551Y1454602D02*
X2279368Y1457518D01*
X2278276Y1460435D01*
Y1472101D01*
X2279368Y1475018D01*
X2281551Y1477935D01*
G01X2293593Y1460435D02*
Y1472101D01*
G01Y1468893D02*
X2294248Y1470352D01*
X2295340Y1471518D01*
X2296868Y1472101D01*
X2298396Y1471518D01*
X2299488Y1470352D01*
X2300143Y1468893D01*
Y1460435D01*
G01Y1468893D02*
X2300798Y1470352D01*
X2301889Y1471518D01*
X2303418Y1472101D01*
X2304946Y1471518D01*
X2306038Y1470352D01*
X2306693Y1468602D01*
Y1460435D01*
G01X2317643Y1472101D02*
Y1460435D01*
G01Y1476768D02*
X2317206Y1477060D01*
Y1477643D01*
X2317643Y1477935D01*
X2318080Y1477643D01*
Y1477060D01*
X2317643Y1476768D01*
G01X2335143Y1460435D02*
Y1477935D01*
G01X2349368Y1462476D02*
X2350460Y1461310D01*
X2351988Y1460435D01*
X2353298D01*
X2354608Y1461018D01*
X2355481Y1461893D01*
X2355918Y1463059D01*
X2355700Y1464810D01*
X2354826Y1465685D01*
X2350896Y1467435D01*
X2350023Y1469477D01*
X2350460Y1470935D01*
X2351333Y1471810D01*
X2352643Y1472101D01*
X2353953Y1471810D01*
X2355263Y1470935D01*
G01X2371235Y1454602D02*
X2373418Y1457518D01*
X2374510Y1460435D01*
Y1472101D01*
X2373418Y1475018D01*
X2371235Y1477935D01*
G01X2225995Y1433076D02*
X2227523Y1435118D01*
X2228833Y1436285D01*
X2230580Y1436868D01*
X2232108Y1436285D01*
X2233200Y1435118D01*
X2234073Y1433368D01*
X2234291Y1431327D01*
X2234073Y1429576D01*
X2233200Y1427826D01*
X2231889Y1426368D01*
X2230361Y1425785D01*
X2228615Y1426368D01*
X2227086Y1428118D01*
X2226213Y1430743D01*
X2225995Y1433660D01*
X2226431Y1437451D01*
X2227086Y1439494D01*
X2228178Y1441535D01*
X2229706Y1442993D01*
X2231235Y1443285D01*
X2232763Y1442702D01*
X2233855Y1441243D01*
G01X2247643Y1425202D02*
X2247206Y1425493D01*
Y1426077D01*
X2247643Y1426368D01*
X2248080Y1426077D01*
Y1425493D01*
X2247643Y1425202D01*
G01X2260340Y1428409D02*
X2261649Y1426951D01*
X2263178Y1426077D01*
X2265143Y1425785D01*
X2267108Y1426368D01*
X2268636Y1427535D01*
X2269728Y1429576D01*
X2269946Y1431910D01*
X2269510Y1434243D01*
X2268418Y1435702D01*
X2266889Y1436868D01*
X2265361Y1437160D01*
X2263833Y1436868D01*
X2261868Y1435702D01*
X2262523Y1443285D01*
X2268418D01*
G01X2278713Y1425202D02*
X2286573Y1443285D01*
G01X2295340Y1428409D02*
X2296649Y1426951D01*
X2298178Y1426077D01*
X2300143Y1425785D01*
X2302108Y1426368D01*
X2303636Y1427535D01*
X2304728Y1429576D01*
X2304946Y1431910D01*
X2304510Y1434243D01*
X2303418Y1435702D01*
X2301889Y1436868D01*
X2300361Y1437160D01*
X2298833Y1436868D01*
X2296868Y1435702D01*
X2297523Y1443285D01*
X2303418D01*
G01X2317643Y1425202D02*
X2317206Y1425493D01*
Y1426077D01*
X2317643Y1426368D01*
X2318080Y1426077D01*
Y1425493D01*
X2317643Y1425202D01*
G01X2335143Y1443285D02*
X2333396Y1442702D01*
X2332086Y1441243D01*
X2331213Y1439494D01*
X2330558Y1437160D01*
X2330340Y1434535D01*
X2330558Y1431910D01*
X2331213Y1429576D01*
X2332086Y1427826D01*
X2333396Y1426368D01*
X2335143Y1425785D01*
X2336889Y1426368D01*
X2338200Y1427826D01*
X2339073Y1429576D01*
X2339728Y1431910D01*
X2339946Y1434535D01*
X2339728Y1437160D01*
X2339073Y1439494D01*
X2338200Y1441243D01*
X2336889Y1442702D01*
X2335143Y1443285D01*
G01X2225340Y1393759D02*
X2226649Y1392301D01*
X2228178Y1391427D01*
X2230143Y1391135D01*
X2232108Y1391718D01*
X2233636Y1392885D01*
X2234728Y1394926D01*
X2234946Y1397260D01*
X2234510Y1399593D01*
X2233418Y1401052D01*
X2231889Y1402218D01*
X2230361Y1402510D01*
X2228833Y1402218D01*
X2226868Y1401052D01*
X2227523Y1408635D01*
X2233418D01*
G01X2247643Y1390552D02*
X2247206Y1390843D01*
Y1391427D01*
X2247643Y1391718D01*
X2248080Y1391427D01*
Y1390843D01*
X2247643Y1390552D01*
G01X2265143Y1408635D02*
X2263396Y1408052D01*
X2262086Y1406593D01*
X2261213Y1404844D01*
X2260558Y1402510D01*
X2260340Y1399885D01*
X2260558Y1397260D01*
X2261213Y1394926D01*
X2262086Y1393176D01*
X2263396Y1391718D01*
X2265143Y1391135D01*
X2266889Y1391718D01*
X2268200Y1393176D01*
X2269073Y1394926D01*
X2269728Y1397260D01*
X2269946Y1399885D01*
X2269728Y1402510D01*
X2269073Y1404844D01*
X2268200Y1406593D01*
X2266889Y1408052D01*
X2265143Y1408635D01*
G01X2278713Y1390552D02*
X2286573Y1408635D01*
G01X2295995Y1398426D02*
X2297523Y1400468D01*
X2298833Y1401635D01*
X2300580Y1402218D01*
X2302108Y1401635D01*
X2303200Y1400468D01*
X2304073Y1398718D01*
X2304291Y1396677D01*
X2304073Y1394926D01*
X2303200Y1393176D01*
X2301889Y1391718D01*
X2300361Y1391135D01*
X2298615Y1391718D01*
X2297086Y1393468D01*
X2296213Y1396093D01*
X2295995Y1399010D01*
X2296431Y1402801D01*
X2297086Y1404844D01*
X2298178Y1406885D01*
X2299706Y1408343D01*
X2301235Y1408635D01*
X2302763Y1408052D01*
X2303855Y1406593D01*
G01X2317643Y1390552D02*
X2317206Y1390843D01*
Y1391427D01*
X2317643Y1391718D01*
X2318080Y1391427D01*
Y1390843D01*
X2317643Y1390552D01*
G01X2330340Y1393759D02*
X2331649Y1392301D01*
X2333178Y1391427D01*
X2335143Y1391135D01*
X2337108Y1391718D01*
X2338636Y1392885D01*
X2339728Y1394926D01*
X2339946Y1397260D01*
X2339510Y1399593D01*
X2338418Y1401052D01*
X2336889Y1402218D01*
X2335361Y1402510D01*
X2333833Y1402218D01*
X2331868Y1401052D01*
X2332523Y1408635D01*
X2338418D01*
G01X2444090Y1425785D02*
Y1443285D01*
X2448456D01*
X2450203Y1442410D01*
X2451513Y1441243D01*
X2452605Y1439494D01*
X2453478Y1437451D01*
X2453696Y1434535D01*
X2453478Y1431618D01*
X2452605Y1429576D01*
X2451513Y1427826D01*
X2450203Y1426660D01*
X2448456Y1425785D01*
X2444090D01*
G01X2462026D02*
Y1443285D01*
X2467266D01*
X2469013Y1442410D01*
X2470323Y1440368D01*
X2470760Y1438035D01*
X2470323Y1435702D01*
X2469231Y1433952D01*
X2467266Y1433076D01*
X2462026D01*
G01X2444090Y1391135D02*
Y1408635D01*
X2448456D01*
X2450203Y1407760D01*
X2451513Y1406593D01*
X2452605Y1404844D01*
X2453478Y1402801D01*
X2453696Y1399885D01*
X2453478Y1396968D01*
X2452605Y1394926D01*
X2451513Y1393176D01*
X2450203Y1392010D01*
X2448456Y1391135D01*
X2444090D01*
G01X2462026D02*
Y1408635D01*
X2467266D01*
X2469013Y1407760D01*
X2470323Y1405718D01*
X2470760Y1403385D01*
X2470323Y1401052D01*
X2469231Y1399302D01*
X2467266Y1398426D01*
X2462026D01*
G01X2431393Y1477935D02*
Y1460435D01*
G01X2426371Y1477935D02*
X2436415D01*
G01X2448893Y1460435D02*
Y1468310D01*
X2444526Y1477935D01*
G01X2453260D02*
X2448893Y1468310D01*
G01X2462026Y1460435D02*
Y1477935D01*
X2467266D01*
X2469013Y1477060D01*
X2470323Y1475018D01*
X2470760Y1472685D01*
X2470323Y1470352D01*
X2469231Y1468602D01*
X2467266Y1467726D01*
X2462026D01*
G01X2488260Y1460435D02*
X2479526D01*
Y1477935D01*
X2488260D01*
G01X2484766Y1469477D02*
X2479526D01*
G01X2532026Y1460435D02*
Y1477935D01*
X2537485D01*
X2539231Y1477060D01*
X2540323Y1475893D01*
X2540760Y1473560D01*
X2540323Y1471226D01*
X2539013Y1469768D01*
X2537485Y1468893D01*
X2532026D01*
G01X2537485D02*
X2540760Y1460435D01*
G01X2550618Y1468310D02*
X2557605D01*
X2556950Y1470352D01*
X2555858Y1471518D01*
X2554330Y1472101D01*
X2552801Y1471810D01*
X2551491Y1470935D01*
X2550618Y1468893D01*
X2550181Y1467143D01*
Y1465393D01*
X2550618Y1463643D01*
X2551710Y1461893D01*
X2553020Y1460727D01*
X2554548Y1460435D01*
X2556076Y1461018D01*
X2557605Y1462768D01*
G01X2570083Y1460435D02*
Y1475310D01*
X2570520Y1476768D01*
X2571393Y1477643D01*
X2572703Y1477935D01*
X2574013Y1477352D01*
X2574668Y1475893D01*
G01X2572048Y1470935D02*
X2567681D01*
G01X2588893Y1459852D02*
X2588456Y1460143D01*
Y1460727D01*
X2588893Y1461018D01*
X2589330Y1460727D01*
Y1460143D01*
X2588893Y1459852D01*
G01X2619526Y1460435D02*
Y1477935D01*
X2624766D01*
X2626513Y1477060D01*
X2627823Y1475018D01*
X2628260Y1472685D01*
X2627823Y1470352D01*
X2626731Y1468602D01*
X2624766Y1467726D01*
X2619526D01*
G01X2641393Y1460435D02*
Y1477935D01*
G01X2662823Y1460435D02*
Y1472101D01*
G01Y1470060D02*
X2661950Y1471226D01*
X2660639Y1471810D01*
X2659111Y1472101D01*
X2657583Y1471518D01*
X2656273Y1470352D01*
X2655399Y1468602D01*
X2654963Y1466268D01*
X2655399Y1463935D01*
X2656273Y1462185D01*
X2657583Y1461018D01*
X2659111Y1460435D01*
X2660639Y1460727D01*
X2661950Y1461601D01*
X2662823Y1462768D01*
G01X2672681Y1460435D02*
Y1472101D01*
G01Y1469185D02*
X2673555Y1470643D01*
X2674865Y1471810D01*
X2676611Y1472101D01*
X2678139Y1471810D01*
X2679450Y1470643D01*
X2680105Y1468602D01*
Y1460435D01*
G01X2690618Y1468310D02*
X2697605D01*
X2696950Y1470352D01*
X2695858Y1471518D01*
X2694330Y1472101D01*
X2692801Y1471810D01*
X2691491Y1470935D01*
X2690618Y1468893D01*
X2690181Y1467143D01*
Y1465393D01*
X2690618Y1463643D01*
X2691710Y1461893D01*
X2693020Y1460727D01*
X2694548Y1460435D01*
X2696076Y1461018D01*
X2697605Y1462768D01*
G01X2602026Y1443285D02*
Y1425785D01*
X2610760D01*
G01X2619745Y1440368D02*
X2621055Y1442118D01*
X2622583Y1442993D01*
X2624330Y1443285D01*
X2626513Y1442702D01*
X2628041Y1441243D01*
X2628478Y1439494D01*
X2628260Y1437743D01*
X2627386Y1436285D01*
X2623020Y1433368D01*
X2621055Y1431327D01*
X2619745Y1428409D01*
X2619308Y1425785D01*
X2628478D01*
G01X2602026Y1408635D02*
Y1391135D01*
X2610760D01*
G01X2619745Y1405718D02*
X2621055Y1407468D01*
X2622583Y1408343D01*
X2624330Y1408635D01*
X2626513Y1408052D01*
X2628041Y1406593D01*
X2628478Y1404844D01*
X2628260Y1403093D01*
X2627386Y1401635D01*
X2623020Y1398718D01*
X2621055Y1396677D01*
X2619745Y1393759D01*
X2619308Y1391135D01*
X2628478D01*
G01X2811693Y1437451D02*
Y1425785D01*
G01Y1442118D02*
X2811256Y1442410D01*
Y1442993D01*
X2811693Y1443285D01*
X2812130Y1442993D01*
Y1442410D01*
X2811693Y1442118D01*
G01X2825918Y1427826D02*
X2827010Y1426660D01*
X2828538Y1425785D01*
X2829848D01*
X2831158Y1426368D01*
X2832031Y1427243D01*
X2832468Y1428409D01*
X2832250Y1430160D01*
X2831376Y1431035D01*
X2827446Y1432785D01*
X2826573Y1434827D01*
X2827010Y1436285D01*
X2827883Y1437160D01*
X2829193Y1437451D01*
X2830503Y1437160D01*
X2831813Y1436285D01*
G01X2859171Y1425785D02*
Y1443285D01*
X2869215Y1425785D01*
Y1443285D01*
G01X2881693Y1425785D02*
X2879946Y1426077D01*
X2878418Y1427243D01*
X2877108Y1428993D01*
X2876234Y1431035D01*
X2875798Y1433368D01*
Y1435702D01*
X2876234Y1438035D01*
X2877108Y1440077D01*
X2878418Y1441826D01*
X2879946Y1442993D01*
X2881693Y1443285D01*
X2883439Y1442993D01*
X2884968Y1441826D01*
X2886278Y1440077D01*
X2887152Y1438035D01*
X2887588Y1435702D01*
Y1433368D01*
X2887152Y1431035D01*
X2886278Y1428993D01*
X2884968Y1427243D01*
X2883439Y1426077D01*
X2881693Y1425785D01*
G01X2899193Y1443285D02*
Y1425785D01*
G01X2894171Y1443285D02*
X2904215D01*
G01X2930481Y1437451D02*
Y1429285D01*
X2931355Y1427243D01*
X2932665Y1426077D01*
X2934193Y1425785D01*
X2935721Y1426077D01*
X2937031Y1427243D01*
X2937905Y1429285D01*
G01Y1425785D02*
Y1437451D01*
G01X2948418Y1427826D02*
X2949510Y1426660D01*
X2951038Y1425785D01*
X2952348D01*
X2953658Y1426368D01*
X2954531Y1427243D01*
X2954968Y1428409D01*
X2954750Y1430160D01*
X2953876Y1431035D01*
X2949946Y1432785D01*
X2949073Y1434827D01*
X2949510Y1436285D01*
X2950383Y1437160D01*
X2951693Y1437451D01*
X2953003Y1437160D01*
X2954313Y1436285D01*
G01X2965918Y1433660D02*
X2972905D01*
X2972250Y1435702D01*
X2971158Y1436868D01*
X2969630Y1437451D01*
X2968101Y1437160D01*
X2966791Y1436285D01*
X2965918Y1434243D01*
X2965481Y1432493D01*
Y1430743D01*
X2965918Y1428993D01*
X2967010Y1427243D01*
X2968320Y1426077D01*
X2969848Y1425785D01*
X2971376Y1426368D01*
X2972905Y1428118D01*
G01X2990623Y1443285D02*
Y1425785D01*
G01Y1428409D02*
X2989750Y1426951D01*
X2988439Y1426077D01*
X2986911Y1425785D01*
X2985165Y1426368D01*
X2983855Y1427826D01*
X2982981Y1429576D01*
X2982763Y1431618D01*
X2982981Y1433660D01*
X2983855Y1435410D01*
X2985165Y1436868D01*
X2986911Y1437451D01*
X2988439Y1437160D01*
X2989531Y1436576D01*
X2990623Y1435410D01*
G01X2736890Y1459852D02*
X2746496Y1472685D01*
G01X2741693Y1475018D02*
Y1457518D01*
G01X2746496Y1459852D02*
X2736890Y1472685D01*
G01X2735143Y1466268D02*
X2748243D01*
G01X2773855D02*
X2779531D01*
G01X2806890Y1460435D02*
Y1477935D01*
X2811256D01*
X2813003Y1477060D01*
X2814313Y1475893D01*
X2815405Y1474144D01*
X2816278Y1472101D01*
X2816496Y1469185D01*
X2816278Y1466268D01*
X2815405Y1464226D01*
X2814313Y1462476D01*
X2813003Y1461310D01*
X2811256Y1460435D01*
X2806890D01*
G01X2825918Y1468310D02*
X2832905D01*
X2832250Y1470352D01*
X2831158Y1471518D01*
X2829630Y1472101D01*
X2828101Y1471810D01*
X2826791Y1470935D01*
X2825918Y1468893D01*
X2825481Y1467143D01*
Y1465393D01*
X2825918Y1463643D01*
X2827010Y1461893D01*
X2828320Y1460727D01*
X2829848Y1460435D01*
X2831376Y1461018D01*
X2832905Y1462768D01*
G01X2842981Y1460435D02*
Y1472101D01*
G01Y1469185D02*
X2843855Y1470643D01*
X2845165Y1471810D01*
X2846911Y1472101D01*
X2848439Y1471810D01*
X2849750Y1470643D01*
X2850405Y1468602D01*
Y1460435D01*
G01X2864193D02*
X2862883Y1460727D01*
X2861573Y1461893D01*
X2860699Y1463935D01*
X2860263Y1466268D01*
X2860699Y1468602D01*
X2861573Y1470643D01*
X2862883Y1471810D01*
X2864193Y1472101D01*
X2865503Y1471810D01*
X2866813Y1470643D01*
X2867686Y1468602D01*
X2867905Y1466268D01*
X2867686Y1463935D01*
X2866813Y1461893D01*
X2865503Y1460727D01*
X2864193Y1460435D01*
G01X2881693Y1477935D02*
Y1460435D01*
G01X2878636Y1472101D02*
X2884750D01*
G01X2895918Y1468310D02*
X2902905D01*
X2902250Y1470352D01*
X2901158Y1471518D01*
X2899630Y1472101D01*
X2898101Y1471810D01*
X2896791Y1470935D01*
X2895918Y1468893D01*
X2895481Y1467143D01*
Y1465393D01*
X2895918Y1463643D01*
X2897010Y1461893D01*
X2898320Y1460727D01*
X2899848Y1460435D01*
X2901376Y1461018D01*
X2902905Y1462768D01*
G01X2913418Y1462476D02*
X2914510Y1461310D01*
X2916038Y1460435D01*
X2917348D01*
X2918658Y1461018D01*
X2919531Y1461893D01*
X2919968Y1463059D01*
X2919750Y1464810D01*
X2918876Y1465685D01*
X2914946Y1467435D01*
X2914073Y1469477D01*
X2914510Y1470935D01*
X2915383Y1471810D01*
X2916693Y1472101D01*
X2918003Y1471810D01*
X2919313Y1470935D01*
G01X2951693Y1477935D02*
Y1460435D01*
G01X2948636Y1472101D02*
X2954750D01*
G01X2965481Y1460435D02*
Y1477935D01*
G01Y1469477D02*
X2966573Y1470935D01*
X2967665Y1471810D01*
X2969411Y1472101D01*
X2970721Y1471810D01*
X2972250Y1470643D01*
X2972905Y1468893D01*
Y1460435D01*
G01X2990623D02*
Y1472101D01*
G01Y1470060D02*
X2989750Y1471226D01*
X2988439Y1471810D01*
X2986911Y1472101D01*
X2985383Y1471518D01*
X2984073Y1470352D01*
X2983199Y1468602D01*
X2982763Y1466268D01*
X2983199Y1463935D01*
X2984073Y1462185D01*
X2985383Y1461018D01*
X2986911Y1460435D01*
X2988439Y1460727D01*
X2989750Y1461601D01*
X2990623Y1462768D01*
G01X3004193Y1477935D02*
Y1460435D01*
G01X3001136Y1472101D02*
X3007250D01*
G01X3039193Y1477935D02*
Y1460435D01*
G01X3036136Y1472101D02*
X3042250D01*
G01X3052981Y1460435D02*
Y1477935D01*
G01Y1469477D02*
X3054073Y1470935D01*
X3055165Y1471810D01*
X3056911Y1472101D01*
X3058221Y1471810D01*
X3059750Y1470643D01*
X3060405Y1468893D01*
Y1460435D01*
G01X3074193Y1472101D02*
Y1460435D01*
G01Y1476768D02*
X3073756Y1477060D01*
Y1477643D01*
X3074193Y1477935D01*
X3074630Y1477643D01*
Y1477060D01*
X3074193Y1476768D01*
G01X3088418Y1462476D02*
X3089510Y1461310D01*
X3091038Y1460435D01*
X3092348D01*
X3093658Y1461018D01*
X3094531Y1461893D01*
X3094968Y1463059D01*
X3094750Y1464810D01*
X3093876Y1465685D01*
X3089946Y1467435D01*
X3089073Y1469477D01*
X3089510Y1470935D01*
X3090383Y1471810D01*
X3091693Y1472101D01*
X3093003Y1471810D01*
X3094313Y1470935D01*
G01X3124073Y1477935D02*
X3129313D01*
G01X3126693D02*
Y1460435D01*
G01X3124073D02*
X3129313D01*
G01X3137643D02*
Y1472101D01*
G01Y1468893D02*
X3138298Y1470352D01*
X3139390Y1471518D01*
X3140918Y1472101D01*
X3142446Y1471518D01*
X3143538Y1470352D01*
X3144193Y1468893D01*
Y1460435D01*
G01Y1468893D02*
X3144848Y1470352D01*
X3145939Y1471518D01*
X3147468Y1472101D01*
X3148996Y1471518D01*
X3150088Y1470352D01*
X3150743Y1468602D01*
Y1460435D01*
G01X3157763Y1454602D02*
Y1472101D01*
G01Y1469477D02*
X3158855Y1470935D01*
X3159946Y1471810D01*
X3161693Y1472101D01*
X3163221Y1471810D01*
X3164750Y1470352D01*
X3165405Y1468310D01*
X3165623Y1466268D01*
X3165405Y1464226D01*
X3164750Y1462185D01*
X3163439Y1461018D01*
X3161693Y1460435D01*
X3160165Y1460727D01*
X3158636Y1461601D01*
X3157763Y1462768D01*
G01X3175918Y1468310D02*
X3182905D01*
X3182250Y1470352D01*
X3181158Y1471518D01*
X3179630Y1472101D01*
X3178101Y1471810D01*
X3176791Y1470935D01*
X3175918Y1468893D01*
X3175481Y1467143D01*
Y1465393D01*
X3175918Y1463643D01*
X3177010Y1461893D01*
X3178320Y1460727D01*
X3179848Y1460435D01*
X3181376Y1461018D01*
X3182905Y1462768D01*
G01X3200623Y1477935D02*
Y1460435D01*
G01Y1463059D02*
X3199750Y1461601D01*
X3198439Y1460727D01*
X3196911Y1460435D01*
X3195165Y1461018D01*
X3193855Y1462476D01*
X3192981Y1464226D01*
X3192763Y1466268D01*
X3192981Y1468310D01*
X3193855Y1470060D01*
X3195165Y1471518D01*
X3196911Y1472101D01*
X3198439Y1471810D01*
X3199531Y1471226D01*
X3200623Y1470060D01*
G01X3218123Y1460435D02*
Y1472101D01*
G01Y1470060D02*
X3217250Y1471226D01*
X3215939Y1471810D01*
X3214411Y1472101D01*
X3212883Y1471518D01*
X3211573Y1470352D01*
X3210699Y1468602D01*
X3210263Y1466268D01*
X3210699Y1463935D01*
X3211573Y1462185D01*
X3212883Y1461018D01*
X3214411Y1460435D01*
X3215939Y1460727D01*
X3217250Y1461601D01*
X3218123Y1462768D01*
G01X3227981Y1460435D02*
Y1472101D01*
G01Y1469185D02*
X3228855Y1470643D01*
X3230165Y1471810D01*
X3231911Y1472101D01*
X3233439Y1471810D01*
X3234750Y1470643D01*
X3235405Y1468602D01*
Y1460435D01*
G01X3252686Y1470643D02*
X3251158Y1471810D01*
X3249848Y1472101D01*
X3248101Y1471518D01*
X3246791Y1470352D01*
X3245918Y1468310D01*
X3245699Y1466268D01*
X3245918Y1464226D01*
X3246791Y1462476D01*
X3248101Y1461018D01*
X3249848Y1460435D01*
X3251376Y1461018D01*
X3252686Y1462185D01*
G01X3263418Y1468310D02*
X3270405D01*
X3269750Y1470352D01*
X3268658Y1471518D01*
X3267130Y1472101D01*
X3265601Y1471810D01*
X3264291Y1470935D01*
X3263418Y1468893D01*
X3262981Y1467143D01*
Y1465393D01*
X3263418Y1463643D01*
X3264510Y1461893D01*
X3265820Y1460727D01*
X3267348Y1460435D01*
X3268876Y1461018D01*
X3270405Y1462768D01*
G01X0Y3937D02*
G03X3937Y0I3937J0D01*
G01X0Y3937D02*
G03X3937Y0I3937J0D01*
G01D02*
X779528D01*
G01X3937D02*
X779528D01*
G01X0Y1456693D02*
Y3937D01*
G01Y1456693D02*
Y3937D01*
G01X7874Y1460630D02*
X3937D01*
G01D02*
X7874D01*
G01X3937D02*
G03X0Y1456693I0J-3937D01*
G01X3937Y1460630D02*
G03X0Y1456693I0J-3937D01*
G01X101378Y1519685D02*
G03X97441Y1515748I0J-3937D01*
G01X101378Y1519685D02*
G03X97441Y1515748I0J-3937D01*
G01D02*
Y1509055D01*
G01Y1515748D02*
Y1509055D01*
G01X93504Y1505118D02*
X67913D01*
G01X93504D02*
G03X97441Y1509055I0J3937D01*
G01X93504Y1505118D02*
G03X97441Y1509055I0J3937D01*
G01X67913Y1505118D02*
X93504D01*
G01X63976Y1515748D02*
G03X60039Y1519685I-3937J0D01*
G01X63976Y1515748D02*
G03X60039Y1519685I-3937J0D01*
G01X63976Y1509055D02*
Y1515748D01*
G01Y1509055D02*
G03X67913Y1505118I3937J0D01*
G01X63976Y1509055D02*
G03X67913Y1505118I3937J0D01*
G01X63976Y1515748D02*
Y1509055D01*
G01X7874Y1460630D02*
G03X11811Y1464567I0J3937D01*
G01X7874Y1460630D02*
G03X11811Y1464567I0J3937D01*
G01X15748Y1519685D02*
G03X11811Y1515748I0J-3937D01*
G01X15748Y1519685D02*
G03X11811Y1515748I0J-3937D01*
G01D02*
Y1464567D01*
G01Y1515748D02*
Y1464567D01*
G01X60039Y1519685D02*
X15748D01*
G01X60039D02*
X15748D01*
G01X141181Y277843D02*
G03X148106Y264712I37662J11471D01*
G01X141181Y277843D02*
G03X148106Y264712I37662J11471D01*
G01X141181Y277843D02*
G03X121220I-9980J-3040D01*
G01X114295Y264712D02*
G03X121220Y277843I-30737J24602D01*
G01X141181D02*
G03X121220I-9980J-3040D01*
G01X114295Y264712D02*
G03X121220Y277843I-30737J24601D01*
G01X114295Y264712D02*
G03X148106I16905J-13531D01*
G01X114295D02*
G03X148106I16905J-13531D01*
G01X141181Y730599D02*
G03X148106Y717468I37662J11471D01*
G01X141181Y730599D02*
G03X148106Y717468I37662J11471D01*
G01X141181Y730599D02*
G03X121220I-9980J-3040D01*
G01X114295Y717468D02*
G03X121220Y730599I-30737J24601D01*
G01X141181D02*
G03X121220I-9980J-3040D01*
G01X114295Y717468D02*
G03X121220Y730599I-30737J24601D01*
G01X114295Y717468D02*
G03X148106I16905J-13531D01*
G01X114295D02*
G03X148106I16905J-13531D01*
G01X114295Y1170224D02*
G03X148106I16905J-13531D01*
G01X114295D02*
G03X148106I16905J-13531D01*
G01X141181Y1183355D02*
G03X148106Y1170224I37662J11471D01*
G01X141181Y1183355D02*
G03X148106Y1170224I37662J11471D01*
G01X141181Y1183355D02*
G03X121220I-9980J-3040D01*
G01X141181D02*
G03X121220I-9980J-3040D01*
G01X114295Y1170224D02*
G03X121220Y1183355I-30737J24602D01*
G01X114295Y1170224D02*
G03X121220Y1183355I-30737J24601D01*
G01X280709Y1519685D02*
X101378D01*
G01X280709D02*
X101378D01*
G01X284646Y1515748D02*
G03X280709Y1519685I-3937J0D01*
G01X284646Y1515748D02*
G03X280709Y1519685I-3937J0D01*
G01X284646Y1500000D02*
Y1515748D01*
G01Y1500000D02*
G03X288583Y1496063I3937J0D01*
G01X493307D02*
X288583D01*
G01X284646Y1500000D02*
G03X288583Y1496063I3937J0D01*
G01X493307D02*
X288583D01*
G01X284646Y1515748D02*
Y1500000D01*
G01X389213Y277843D02*
G03X369252I-9981J-3040D01*
G01X389213D02*
G03X369252I-9981J-3040D01*
G01X362327Y264712D02*
G03X369252Y277843I-30737J24602D01*
G01X362327Y264712D02*
G03X369252Y277843I-30737J24602D01*
G01X362327Y264712D02*
G03X396138I16905J-13531D01*
G01X362327D02*
G03X396138I16905J-13531D01*
G01X389213Y730599D02*
G03X369252I-9981J-3040D01*
G01X389213D02*
G03X369252I-9981J-3040D01*
G01X362327Y717468D02*
G03X369252Y730599I-30737J24602D01*
G01X362327Y717468D02*
G03X369252Y730599I-30737J24602D01*
G01X362327Y717468D02*
G03X396138I16905J-13531D01*
G01X362327D02*
G03X396138I16905J-13531D01*
G01X362327Y1170224D02*
G03X396138I16905J-13531D01*
G01X362327D02*
G03X396138I16905J-13531D01*
G01X389213Y1183355D02*
G03X369252I-9981J-3040D01*
G01X389213D02*
G03X369252I-9981J-3040D01*
G01X362327Y1170224D02*
G03X369252Y1183355I-30737J24602D01*
G01X362327Y1170224D02*
G03X369252Y1183355I-30737J24602D01*
G01X322441Y1503937D02*
G03Y1496063I0J-3937D01*
G01X459449Y1503937D02*
X322441D01*
G01X459449D02*
X322441D01*
G01D02*
G03Y1496063I0J-3937D01*
G01X296457Y1519685D02*
G03X292520Y1515748I0J-3937D01*
G01X296457Y1519685D02*
X485433D01*
G01X296457D02*
G03X292520Y1515748I0J-3937D01*
G01X296457Y1519685D02*
X485433D01*
G01X304331Y1503937D02*
X292520D01*
G01Y1515748D02*
Y1503937D01*
G01X304331D02*
X292520D01*
G01Y1515748D02*
Y1503937D01*
G01X304331Y1496063D02*
G03Y1503937I0J3937D01*
G01Y1496063D02*
G03Y1503937I0J3937D01*
G01X389213Y277843D02*
G03X396138Y264712I37662J11471D01*
G01X389213Y277843D02*
G03X396138Y264712I37662J11470D01*
G01X389213Y730599D02*
G03X396138Y717468I37662J11471D01*
G01X389213Y730599D02*
G03X396138Y717468I37662J11470D01*
G01X389213Y1183355D02*
G03X396138Y1170224I37662J11471D01*
G01X389213Y1183355D02*
G03X396138Y1170224I37662J11470D01*
G01X477559Y1503937D02*
G03Y1496063I0J-3937D01*
G01X459449D02*
G03Y1503937I0J3937D01*
G01X489370D02*
X477559D01*
G01D02*
G03Y1496063I0J-3937D01*
G01X459449D02*
G03Y1503937I0J3937D01*
G01X489370D02*
X477559D01*
G01X489370Y1515748D02*
G03X485433Y1519685I-3937J0D01*
G01X489370Y1515748D02*
G03X485433Y1519685I-3937J0D01*
G01X501181D02*
G03X497244Y1515748I0J-3937D01*
G01X680512Y1519685D02*
X501181D01*
G01D02*
G03X497244Y1515748I0J-3937D01*
G01X680512Y1519685D02*
X501181D01*
G01X489370Y1515748D02*
Y1503937D01*
G01X493307Y1496063D02*
G03X497244Y1500000I0J3937D01*
G01Y1515748D02*
Y1500000D01*
G01X489370Y1515748D02*
Y1503937D01*
G01X493307Y1496063D02*
G03X497244Y1500000I0J3937D01*
G01Y1515748D02*
Y1500000D01*
G01X637244Y277843D02*
G03X644169Y264712I37662J11471D01*
G01X637244Y277843D02*
G03X644169Y264712I37662J11471D01*
G01X637244Y277843D02*
G03X617283I-9980J-3040D01*
G01X610358Y264712D02*
G03X617283Y277843I-30737J24602D01*
G01X637244D02*
G03X617283I-9980J-3040D01*
G01X610358Y264712D02*
G03X617283Y277843I-30737J24601D01*
G01X610358Y264712D02*
G03X644169I16906J-13531D01*
G01X610358D02*
G03X644169I16906J-13531D01*
G01X637244Y730599D02*
G03X644169Y717468I37662J11471D01*
G01X637244Y730599D02*
G03X644169Y717468I37662J11471D01*
G01X637244Y730599D02*
G03X617283I-9980J-3040D01*
G01X610358Y717468D02*
G03X617283Y730599I-30737J24601D01*
G01X637244D02*
G03X617283I-9980J-3040D01*
G01X610358Y717468D02*
G03X617283Y730599I-30737J24601D01*
G01X610358Y717468D02*
G03X644169I16906J-13531D01*
G01X610358D02*
G03X644169I16906J-13531D01*
G01X610358Y1170224D02*
G03X644169I16906J-13531D01*
G01X610358D02*
G03X644169I16906J-13531D01*
G01X637244Y1183355D02*
G03X644169Y1170224I37662J11471D01*
G01X637244Y1183355D02*
G03X644169Y1170224I37662J11471D01*
G01X637244Y1183355D02*
G03X617283I-9980J-3040D01*
G01X637244D02*
G03X617283I-9980J-3040D01*
G01X610358Y1170224D02*
G03X617283Y1183355I-30737J24602D01*
G01X610358Y1170224D02*
G03X617283Y1183355I-30737J24601D01*
G01X730339Y383610D02*
G03X764149I16905J-13531D01*
G01X730339Y383609D02*
G03X764150I16905J-13530D01*
G01X757225Y396741D02*
G03X764149Y383610I37663J11469D01*
G01X757224Y396741D02*
G03X764150Y383609I37662J11471D01*
G01X757225Y396741D02*
G03X737264I-9981J-3040D01*
G01X730339Y383610D02*
G03X737264Y396741I-30737J24602D01*
G01X757224D02*
G03X737264I-9980J-3041D01*
G01X730339Y383609D02*
G03X737264Y396741I-30738J24601D01*
G01X757225Y829811D02*
G03X764149Y816680I37663J11469D01*
G01X757224Y829811D02*
G03X764150Y816680I37662J11473D01*
G01X757225Y829811D02*
G03X737264I-9981J-3039D01*
G01X757224D02*
G03X737264I-9980J-3040D01*
G01X730339Y816680D02*
G03X737264Y829811I-30737J24602D01*
G01X730339Y816680D02*
G03X737264Y829811I-30737J24602D01*
G01X730339Y816680D02*
G03X764149I16905J-13531D01*
G01X730339D02*
G03X764150I16905J-13531D01*
G01X721850Y1519685D02*
G03X717913Y1515748I0J-3937D01*
G01X775591Y1519685D02*
X721850D01*
G01D02*
G03X717913Y1515748I0J-3937D01*
G01X775591Y1519685D02*
X721850D01*
G01X713976Y1505118D02*
G03X717913Y1509055I0J3937D01*
G01Y1515748D02*
Y1509055D01*
G01X713976Y1505118D02*
G03X717913Y1509055I0J3937D01*
G01Y1515748D02*
Y1509055D01*
G01X684449Y1515748D02*
G03X680512Y1519685I-3937J0D01*
G01X684449Y1515748D02*
G03X680512Y1519685I-3937J0D01*
G01X684449Y1509055D02*
Y1515748D01*
G01Y1509055D02*
G03X688386Y1505118I3937J0D01*
G01X713976D02*
X688386D01*
G01X684449Y1509055D02*
G03X688386Y1505118I3937J0D01*
G01D02*
X713976D01*
G01X684449Y1515748D02*
Y1509055D01*
G01X791339Y3937D02*
G03X795276Y0I3937J0D01*
G01D02*
X892317D01*
G01X791339Y3937D02*
Y23622D01*
G01Y3937D02*
G03X795276Y0I3937J0D01*
G01X791339Y3937D02*
Y23622D01*
G01X795276Y0D02*
X892317D01*
G01X783465Y54331D02*
G03X791339I3937J0D01*
G01X783465D02*
G03X791339I3937J0D01*
G01Y23622D02*
G03X783465I-3937J0D01*
G01X791339D02*
G03X783465I-3937J0D01*
G01X779528Y0D02*
G03X783465Y3937I0J3937D01*
G01X779528Y0D02*
G03X783465Y3937I0J3937D01*
G01X791339Y54331D02*
Y181890D01*
G01Y54331D02*
Y181890D01*
G01X783465Y3937D02*
Y185827D01*
G01Y3937D02*
Y185827D01*
G01X811024Y181890D02*
G03X822835Y193701I0J11811D01*
G01X791339Y181890D02*
X811024D01*
G01D02*
G03X822835Y193701I0J11811D01*
G01X791339Y181890D02*
X811024D01*
G01X787402Y189764D02*
G03X783465Y185827I0J-3937D01*
G01X787402Y189764D02*
G03X783465Y185827I0J-3937D01*
G01X811024Y189764D02*
G03X814961Y193701I0J3937D01*
G01X787402Y189764D02*
X811024D01*
G01D02*
G03X814961Y193701I0J3937D01*
G01X787402Y189764D02*
X811024D01*
G01X822835Y193701D02*
Y240157D01*
G01Y193701D02*
Y240157D01*
G01X814961Y193701D02*
Y244094D01*
G01Y193701D02*
Y244094D01*
G01X818898Y248031D02*
G03X814961Y244094I0J-3937D01*
G01X818898Y248031D02*
G03X814961Y244094I0J-3937D01*
G01X928098Y240157D02*
X822835D01*
G01X928098D02*
X822835D01*
G01X818898Y248031D02*
X1055118D01*
G01D02*
X818898D01*
G01X954331Y1503937D02*
X817323D01*
G01X954331D02*
X817323D01*
G01X791339Y1519685D02*
G03X787402Y1515748I0J-3937D01*
G01X791339Y1519685D02*
X980315D01*
G01X791339D02*
G03X787402Y1515748I0J-3937D01*
G01X791339Y1519685D02*
X980315D01*
G01X817323Y1503937D02*
G03Y1496063I0J-3937D01*
G01X799213D02*
G03Y1503937I0J3937D01*
G01D02*
X787402D01*
G01Y1515748D02*
Y1503937D01*
G01X799213D02*
X787402D01*
G01X817323D02*
G03Y1496063I0J-3937D01*
G01X799213D02*
G03Y1503937I0J3937D01*
G01X787402Y1515748D02*
Y1503937D01*
G01X779528Y1515748D02*
G03X775591Y1519685I-3937J0D01*
G01X779528Y1515748D02*
G03X775591Y1519685I-3937J0D01*
G01X779528Y1500000D02*
Y1515748D01*
G01Y1500000D02*
G03X783465Y1496063I3937J0D01*
G01X988189D02*
X783465D01*
G01X779528Y1500000D02*
G03X783465Y1496063I3937J0D01*
G01X988189D02*
X783465D01*
G01X779528Y1515748D02*
Y1500000D01*
G01X900191Y0D02*
G03X892317I-3937J0D01*
G01X896254D02*
Y-394D01*
G01Y0D02*
Y394D01*
G01X895762Y0D02*
X896746D01*
G01X900191D02*
G03X892317I-3937J0D01*
G01X900191D02*
X1212598D01*
G01X900191D02*
X1212598D01*
G01X953294Y248031D02*
G03Y240157I1J-3937D01*
G01X1051181D02*
X953294D01*
G01Y248031D02*
G03Y240157I1J-3937D01*
G01X928098D02*
G03Y248031I0J3937D01*
G01Y240157D02*
G03Y248031I0J3937D01*
G01X1051181Y240157D02*
X953294D01*
G01X971398Y718788D02*
G03X951437I-9980J-3040D01*
G01X944512Y705657D02*
G03X951437Y718788I-30737J24602D01*
G01X971398D02*
G03X951437I-9980J-3040D01*
G01X944512Y705657D02*
G03X951437Y718788I-30737J24602D01*
G01X944512Y705657D02*
G03X978323I16905J-13531D01*
G01X944512D02*
G03X978323I16905J-13531D01*
G01X944512Y974161D02*
G03X978323I16905J-13531D01*
G01X944512D02*
G03X978323I16905J-13531D01*
G01X971398Y987292D02*
G03X951437I-9980J-3040D01*
G01X944512Y974161D02*
G03X951437Y987292I-30737J24602D01*
G01X971398D02*
G03X951437I-9980J-3040D01*
G01X944512Y974161D02*
G03X951437Y987292I-30737J24602D01*
G01X954331Y1496063D02*
G03Y1503937I0J3937D01*
G01Y1496063D02*
G03Y1503937I0J3937D01*
G01X1051181Y193701D02*
G03X1062992Y181890I11811J0D01*
G01X1051181Y193701D02*
G03X1062992Y181890I11811J0D01*
G01X1051181Y240157D02*
Y193701D01*
G01Y240157D02*
Y193701D01*
G01X971398Y718788D02*
G03X978323Y705657I37662J11471D01*
G01X971398Y718788D02*
G03X978323Y705657I37662J11470D01*
G01X971398Y987292D02*
G03X978323Y974161I37662J11471D01*
G01X971398Y987292D02*
G03X978323Y974161I37662J11470D01*
G01X1059196Y1519685D02*
X996063D01*
G01X1059196D02*
X996063D01*
G01X984252Y1515748D02*
G03X980315Y1519685I-3937J0D01*
G01X984252Y1515748D02*
G03X980315Y1519685I-3937J0D01*
G01X996063D02*
G03X992126Y1515748I0J-3937D01*
G01X996063Y1519685D02*
G03X992126Y1515748I0J-3937D01*
G01X972441Y1503937D02*
G03Y1496063I0J-3937D01*
G01X984252Y1503937D02*
X972441D01*
G01X984252Y1515748D02*
Y1503937D01*
G01X972441D02*
G03Y1496063I0J-3937D01*
G01X988189D02*
G03X992126Y1500000I0J3937D01*
G01Y1515748D02*
Y1500000D01*
G01X984252Y1515748D02*
Y1503937D01*
G01D02*
X972441D01*
G01X988189Y1496063D02*
G03X992126Y1500000I0J3937D01*
G01Y1515748D02*
Y1500000D01*
G01X1133071Y189764D02*
G03Y181890I0J-3937D01*
G01D02*
X1216535D01*
G01X1133071D02*
X1216535D01*
G01X1133071Y189764D02*
G03Y181890I0J-3937D01*
G01X1102362D02*
G03Y189764I0J3937D01*
G01Y181890D02*
G03Y189764I0J3937D01*
G01X1062992Y181890D02*
X1102362D01*
G01X1062992D02*
X1102362D01*
G01X1059055Y244094D02*
G03X1055118Y248031I-3937J0D01*
G01X1059055Y244094D02*
G03X1055118Y248031I-3937J0D01*
G01X1059055Y244094D02*
Y193701D01*
G01Y244094D02*
Y193701D01*
G01X1062992Y189764D02*
X1220472D01*
G01X1059055Y193701D02*
G03X1062992Y189764I3937J0D01*
G01X1059055Y193701D02*
G03X1062992Y189764I3937J0D01*
G01D02*
X1220472D01*
G01X1085630Y1417323D02*
G03X1089567Y1421260I0J3937D01*
G01X1085630Y1417323D02*
G03X1089567Y1421260I0J3937D01*
G01X1072638D02*
G03X1076575Y1417322I3937J-1D01*
G01X1085630Y1417323D02*
X1076575D01*
G01X1072638Y1421260D02*
G03X1076575Y1417323I3937J0D01*
G01D02*
X1085630D01*
G01X1089567Y1506243D02*
Y1421260D01*
G01Y1506243D02*
Y1421260D01*
G01X1072638D02*
Y1506243D01*
G01D02*
Y1421260D01*
G01X1103009Y1519685D02*
G03X1100225Y1518532I0J-3937D01*
G01X1207283Y1519685D02*
X1103009D01*
G01D02*
G03X1100225Y1518532I0J-3937D01*
G01X1207283Y1519685D02*
X1103009D01*
G01X1090720Y1509027D02*
G03X1089567Y1506243I2784J-2784D01*
G01X1100225Y1518532D02*
X1090720Y1509027D01*
G01D02*
G03X1089567Y1506243I2784J-2784D01*
G01X1100225Y1518532D02*
X1090720Y1509027D01*
G01X1061980Y1518532D02*
G03X1059196Y1519685I-2784J-2784D01*
G01X1061980Y1518532D02*
G03X1059196Y1519685I-2784J-2784D01*
G01X1071485Y1509027D02*
X1061980Y1518532D01*
G01X1072638Y1506243D02*
G03X1071485Y1509027I-3937J0D01*
G01X1072638Y1506243D02*
G03X1071485Y1509027I-3937J0D01*
G01X1061980Y1518532D02*
X1071485Y1509027D01*
G01X1216535Y54331D02*
G03X1224409I3937J0D01*
G01X1216535D02*
Y181890D01*
G01Y54331D02*
Y181890D01*
G01Y54331D02*
G03X1224409I3937J0D01*
G01Y23622D02*
G03X1216535I-3937J0D01*
G01X1224409D02*
G03X1216535I-3937J0D01*
G01X1212598Y0D02*
G03X1216535Y3937I0J3937D01*
G01D02*
Y23622D01*
G01X1212598Y0D02*
G03X1216535Y3937I0J3937D01*
G01X1224409D02*
G03X1228346Y0I3937J0D01*
G01X1224409Y185827D02*
Y3937D01*
G01X1216535D02*
Y23622D01*
G01X1224409Y3937D02*
G03X1228346Y0I3937J0D01*
G01X1224409Y3937D02*
Y185827D01*
G01X1228346Y0D02*
X1930906D01*
G01X1228346D02*
X1930906D01*
G01X1224409Y185827D02*
G03X1220472Y189764I-3937J0D01*
G01X1224409Y185827D02*
G03X1220472Y189764I-3937J0D01*
G01X1164984Y383609D02*
G03X1198795I16906J-13530D01*
G01X1164984D02*
G03X1198795I16906J-13530D01*
G01X1191870Y396741D02*
G03X1198795Y383610I37662J11471D01*
G01X1191870Y396741D02*
G03X1198795Y383609I37663J11469D01*
G01X1191870Y396741D02*
G03X1171909I-9980J-3040D01*
G01X1164984Y383610D02*
G03X1171909Y396741I-30737J24602D01*
G01X1191870D02*
G03X1171909I-9980J-3040D01*
G01X1164984Y383609D02*
G03X1171909Y396741I-30737J24601D01*
G01X1164984Y974161D02*
G03X1198795I16906J-13531D01*
G01X1164984D02*
G03X1198795I16906J-13531D01*
G01X1191870Y987292D02*
G03X1198795Y974161I37662J11471D01*
G01X1191870Y987292D02*
G03X1198795Y974161I37662J11471D01*
G01X1191870Y987292D02*
G03X1171909I-9980J-3040D01*
G01X1164984Y974161D02*
G03X1171909Y987292I-30737J24602D01*
G01X1191870D02*
G03X1171909I-9980J-3040D01*
G01X1164984Y974161D02*
G03X1171909Y987292I-30737J24601D01*
G01X1240748Y1505118D02*
G03X1244685Y1509055I0J3937D01*
G01X1240748Y1505118D02*
G03X1244685Y1509055I0J3937D01*
G01X1211220Y1515748D02*
G03X1207283Y1519685I-3937J0D01*
G01X1211220Y1515748D02*
G03X1207283Y1519685I-3937J0D01*
G01X1211220Y1509055D02*
Y1515748D01*
G01Y1509055D02*
G03X1215157Y1505118I3937J0D01*
G01X1240748D02*
X1215157D01*
G01X1211220Y1509055D02*
G03X1215157Y1505118I3937J0D01*
G01D02*
X1240748D01*
G01X1211220Y1515748D02*
Y1509055D01*
G01X1311851Y277843D02*
G03X1318775Y264712I37663J11469D01*
G01X1311850Y277843D02*
G03X1318776Y264712I37661J11473D01*
G01X1311851Y277843D02*
G03X1291890I-9980J-3040D01*
G01X1284965Y264712D02*
G03X1291890Y277843I-30737J24602D01*
G01X1311850D02*
G03X1291890I-9980J-3040D01*
G01X1284965Y264712D02*
G03X1291890Y277843I-30737J24602D01*
G01X1284965Y264712D02*
G03X1318775I16905J-13531D01*
G01X1284965D02*
G03X1318776I16906J-13531D01*
G01X1311851Y730599D02*
G03X1318775Y717468I37663J11469D01*
G01X1311850Y730599D02*
G03X1318776Y717468I37661J11473D01*
G01X1311851Y730599D02*
G03X1291890I-9980J-3040D01*
G01X1284965Y717468D02*
G03X1291891Y730599I-30736J24604D01*
G01X1311850D02*
G03X1291890I-9980J-3040D01*
G01X1284965Y717468D02*
G03X1291890Y730599I-30737J24602D01*
G01X1284965Y717468D02*
G03X1318775I16905J-13531D01*
G01X1284965D02*
G03X1318776I16906J-13531D01*
G01X1284965Y1170224D02*
G03X1318775I16905J-13531D01*
G01X1284965D02*
G03X1318776I16906J-13531D01*
G01X1311851Y1183355D02*
G03X1318775Y1170224I37663J11469D01*
G01X1311850Y1183355D02*
G03X1318776Y1170224I37661J11473D01*
G01X1311851Y1183355D02*
G03X1291890I-9980J-3040D01*
G01X1311850D02*
G03X1291890I-9980J-3040D01*
G01X1284965Y1170224D02*
G03X1291890Y1183355I-30737J24602D01*
G01X1284965Y1170224D02*
G03X1291890Y1183355I-30737J24602D01*
G01X1248622Y1519685D02*
G03X1244685Y1515748I0J-3937D01*
G01X1427953Y1519685D02*
X1248622D01*
G01D02*
G03X1244685Y1515748I0J-3937D01*
G01X1427953Y1519685D02*
X1248622D01*
G01X1244685Y1515748D02*
Y1509055D01*
G01Y1515748D02*
Y1509055D01*
G01X1431890Y1515748D02*
G03X1427953Y1519685I-3937J0D01*
G01X1431890Y1515748D02*
G03X1427953Y1519685I-3937J0D01*
G01X1431890Y1500000D02*
Y1515748D01*
G01Y1500000D02*
G03X1435827Y1496063I3937J0D01*
G01X1431890Y1500000D02*
G03X1435827Y1496063I3937J0D01*
G01X1431890Y1515748D02*
Y1500000D01*
G01X1532996Y264712D02*
G03X1566807I16906J-13531D01*
G01X1532996D02*
G03X1566807I16906J-13531D01*
G01X1532996Y717468D02*
G03X1566807I16906J-13531D01*
G01X1532996D02*
G03X1566807I16906J-13531D01*
G01X1532996Y1170224D02*
G03X1566807I16906J-13531D01*
G01X1532996D02*
G03X1566807I16906J-13531D01*
G01X1469685Y1503937D02*
G03Y1496063I0J-3937D01*
G01X1451575D02*
G03Y1503937I0J3937D01*
G01X1606693D02*
X1469685D01*
G01X1606693D02*
X1469685D01*
G01D02*
G03Y1496063I0J-3937D01*
G01X1451575D02*
G03Y1503937I0J3937D01*
G01X1443701Y1519685D02*
G03X1439764Y1515748I0J-3937D01*
G01X1443701Y1519685D02*
X1632677D01*
G01X1443701D02*
G03X1439764Y1515748I0J-3937D01*
G01X1443701Y1519685D02*
X1632677D01*
G01X1451575Y1503937D02*
X1439764D01*
G01Y1515748D02*
Y1503937D01*
G01X1451575D02*
X1439764D01*
G01X1640551Y1496063D02*
X1435827D01*
G01X1439764Y1515748D02*
Y1503937D01*
G01X1640551Y1496063D02*
X1435827D01*
G01X1559882Y277843D02*
G03X1566807Y264712I37662J11471D01*
G01X1559882Y277843D02*
G03X1539921I-9980J-3040D01*
G01X1559882D02*
G03X1566807Y264712I37662J11471D01*
G01X1559882Y277843D02*
G03X1539921I-9980J-3040D01*
G01X1532996Y264712D02*
G03X1539921Y277843I-30737J24602D01*
G01X1532996Y264712D02*
G03X1539921Y277843I-30737J24602D01*
G01X1559882Y730599D02*
G03X1566807Y717468I37662J11471D01*
G01X1559882Y730599D02*
G03X1539921I-9980J-3040D01*
G01X1559882D02*
G03X1566807Y717468I37662J11471D01*
G01X1559882Y730599D02*
G03X1539921I-9980J-3040D01*
G01X1532996Y717468D02*
G03X1539921Y730599I-30737J24601D01*
G01X1532996Y717468D02*
G03X1539921Y730599I-30737J24601D01*
G01X1559882Y1183355D02*
G03X1539921I-9980J-3040D01*
G01X1559882D02*
G03X1539921I-9980J-3040D01*
G01X1559882D02*
G03X1566807Y1170224I37662J11471D01*
G01X1559882Y1183355D02*
G03X1566807Y1170224I37662J11471D01*
G01X1532996D02*
G03X1539921Y1183355I-30737J24602D01*
G01X1532996Y1170224D02*
G03X1539921Y1183355I-30737J24601D01*
G01X1636614Y1503937D02*
X1624803D01*
G01X1636614D02*
X1624803D01*
G01D02*
G03Y1496063I0J-3937D01*
G01X1606693D02*
G03Y1503937I0J3937D01*
G01X1624803D02*
G03Y1496063I0J-3937D01*
G01X1606693D02*
G03Y1503937I0J3937D01*
G01X1636614Y1515748D02*
G03X1632677Y1519685I-3937J0D01*
G01X1636614Y1515748D02*
G03X1632677Y1519685I-3937J0D01*
G01X1648425D02*
G03X1644488Y1515748I0J-3937D01*
G01X1827756Y1519685D02*
X1648425D01*
G01D02*
G03X1644488Y1515748I0J-3937D01*
G01X1827756Y1519685D02*
X1648425D01*
G01X1636614Y1515748D02*
Y1503937D01*
G01X1640551Y1496063D02*
G03X1644488Y1500000I0J3937D01*
G01Y1515748D02*
Y1500000D01*
G01X1636614Y1515748D02*
Y1503937D01*
G01X1640551Y1496063D02*
G03X1644488Y1500000I0J3937D01*
G01Y1515748D02*
Y1500000D01*
G01X1807914Y277843D02*
G03X1814838Y264712I37663J11469D01*
G01X1807913Y277843D02*
G03X1814839Y264712I37661J11473D01*
G01X1807914Y277843D02*
G03X1787953I-9980J-3040D01*
G01X1781028Y264712D02*
G03X1787953Y277843I-30737J24602D01*
G01X1807913D02*
G03X1787953I-9980J-3040D01*
G01X1781028Y264712D02*
G03X1787953Y277843I-30737J24602D01*
G01X1781028Y264712D02*
G03X1814839I16906J-13531D01*
G01X1781028D02*
G03X1814839I16906J-13531D01*
G01X1807914Y730599D02*
G03X1814838Y717468I37663J11469D01*
G01X1807913Y730599D02*
G03X1814839Y717468I37661J11473D01*
G01X1807914Y730599D02*
G03X1787953I-9980J-3040D01*
G01X1781028Y717468D02*
G03X1787954Y730599I-30736J24604D01*
G01X1807913D02*
G03X1787953I-9980J-3040D01*
G01X1781028Y717468D02*
G03X1787953Y730599I-30737J24602D01*
G01X1781028Y717468D02*
G03X1814838I16905J-13531D01*
G01X1781028D02*
G03X1814839I16906J-13531D01*
G01X1781028Y1170224D02*
G03X1814838I16905J-13531D01*
G01X1781028D02*
G03X1814839I16906J-13531D01*
G01X1807914Y1183355D02*
G03X1814838Y1170224I37662J11468D01*
G01X1807913Y1183355D02*
G03X1814839Y1170224I37661J11473D01*
G01X1807914Y1183355D02*
G03X1787953I-9980J-3040D01*
G01X1807913D02*
G03X1787953I-9980J-3040D01*
G01X1781028Y1170224D02*
G03X1787953Y1183355I-30737J24602D01*
G01X1781028Y1170224D02*
G03X1787953Y1183355I-30737J24602D01*
G01X1869094Y1519685D02*
G03X1865157Y1515748I0J-3937D01*
G01X1919094Y1519685D02*
X1869094D01*
G01D02*
G03X1865157Y1515748I0J-3937D01*
G01X1919094Y1519685D02*
X1869094D01*
G01X1865157Y1515748D02*
Y1509055D01*
G01Y1515748D02*
Y1509055D01*
G01X1861220Y1505118D02*
X1835630D01*
G01X1861220D02*
G03X1865157Y1509055I0J3937D01*
G01X1861220Y1505118D02*
G03X1865157Y1509055I0J3937D01*
G01X1835630Y1505118D02*
X1861220D01*
G01X1831693Y1515748D02*
G03X1827756Y1519685I-3937J0D01*
G01X1831693Y1515748D02*
G03X1827756Y1519685I-3937J0D01*
G01X1831693Y1509055D02*
Y1515748D01*
G01Y1509055D02*
G03X1835630Y1505118I3937J0D01*
G01X1831693Y1509055D02*
G03X1835630Y1505118I3937J0D01*
G01X1831693Y1515748D02*
Y1509055D01*
G01X1930906Y0D02*
G03X1934843Y3937I0J3937D01*
G01X1930906Y0D02*
G03X1934843Y3937I0J3937D01*
G01D02*
Y1456693D01*
G01Y3937D02*
Y1456693D01*
G01X1930906Y1460630D02*
X1926969D01*
G01X1934843Y1456693D02*
G03X1930906Y1460630I-3937J0D01*
G01X1934843Y1456693D02*
G03X1930906Y1460630I-3937J0D01*
G01D02*
X1926969D01*
G01X1923031Y1515748D02*
G03X1919094Y1519685I-3937J0D01*
G01X1923031Y1515748D02*
G03X1919094Y1519685I-3937J0D01*
G01X1923031Y1464567D02*
Y1515748D01*
G01Y1464567D02*
G03X1926969Y1460630I3937J0D01*
G01X1923031Y1464567D02*
G03X1926969Y1460630I3937J0D01*
G01X1923031Y1515748D02*
Y1464567D01*
M02*
